G04 ================== begin FILE IDENTIFICATION RECORD ==================*
G04 Layout Name:  D:/<user>/Wistron_project/16318-2/gbr/16318-2.brd*
G04 Film Name:    BSMD*
G04 File Format:  Gerber RS274X*
G04 File Origin:  Cadence Allegro 16.5-S056*
G04 Origin Date:  Mon Aug 07 11:09:16 2017*
G04 *
G04 Layer:  VIA CLASS/PASTEMASK_BOTTOM*
G04 Layer:  PIN/PASTEMASK_BOTTOM*
G04 Layer:  PACKAGE GEOMETRY/PASTEMASK_BOTTOM*
G04 Layer:  DRAWING FORMAT/LAYER_PCB_STORY*
G04 Layer:  DRAWING FORMAT/LAYER_PAST_B*
G04 Layer:  BOARD GEOMETRY/PANEL_OUTLINE*
G04 *
G04 Offset:    (0.00 0.00)*
G04 Mirror:    No*
G04 Mode:      Positive*
G04 Rotation:  0*
G04 FullContactRelief:  No*
G04 UndefLineWidth:     6.00*
G04 ================== end FILE IDENTIFICATION RECORD ====================*
%FSLAX35Y35*MOIN*%
%IR0*IPPOS*OFA0.00000B0.00000*MIA0B0*SFA1.00000B1.00000*%
%AMMACRO26*
4,1,40,.011,.007,
.011,-.007,
.010939,-.007695,
.010759,-.008368,
.010464,-.009,
.010064,-.009571,
.009571,-.010064,
.009,-.010464,
.008368,-.010759,
.007695,-.010939,
.007,-.011,
-.007,-.011,
-.007695,-.010939,
-.008368,-.010759,
-.009,-.010464,
-.009571,-.010064,
-.010064,-.009571,
-.010464,-.009,
-.010759,-.008368,
-.010939,-.007695,
-.011,-.007,
-.011,.007,
-.010939,.007695,
-.010759,.008368,
-.010464,.009,
-.010064,.009571,
-.009571,.010064,
-.009,.010464,
-.008368,.010759,
-.007695,.010939,
-.007,.011,
.007,.011,
.007695,.010939,
.008368,.010759,
.009,.010464,
.009571,.010064,
.010064,.009571,
.010464,.009,
.010759,.008368,
.010939,.007695,
.011,.007,
0.0*
%
%ADD26MACRO26*%
%AMMACRO21*
4,1,40,.013,-.017,
-.013,-.017,
-.013695,-.016939,
-.014368,-.016759,
-.015,-.016464,
-.015571,-.016064,
-.016064,-.015571,
-.016464,-.015,
-.016759,-.014368,
-.016939,-.013695,
-.017,-.013,
-.017,.013,
-.016939,.013695,
-.016759,.014368,
-.016464,.015,
-.016064,.015571,
-.015571,.016064,
-.015,.016464,
-.014368,.016759,
-.013695,.016939,
-.013,.017,
.013,.017,
.013695,.016939,
.014368,.016759,
.015,.016464,
.015571,.016064,
.016064,.015571,
.016464,.015,
.016759,.014368,
.016939,.013695,
.017,.013,
.017,-.013,
.016939,-.013695,
.016759,-.014368,
.016464,-.015,
.016064,-.015571,
.015571,-.016064,
.015,-.016464,
.014368,-.016759,
.013695,-.016939,
.013,-.017,
0.0*
%
%ADD21MACRO21*%
%AMMACRO19*
4,1,40,-.017,-.013,
-.017,.013,
-.016939,.013695,
-.016759,.014368,
-.016464,.015,
-.016064,.015571,
-.015571,.016064,
-.015,.016464,
-.014368,.016759,
-.013695,.016939,
-.013,.017,
.013,.017,
.013695,.016939,
.014368,.016759,
.015,.016464,
.015571,.016064,
.016064,.015571,
.016464,.015,
.016759,.014368,
.016939,.013695,
.017,.013,
.017,-.013,
.016939,-.013695,
.016759,-.014368,
.016464,-.015,
.016064,-.015571,
.015571,-.016064,
.015,-.016464,
.014368,-.016759,
.013695,-.016939,
.013,-.017,
-.013,-.017,
-.013695,-.016939,
-.014368,-.016759,
-.015,-.016464,
-.015571,-.016064,
-.016064,-.015571,
-.016464,-.015,
-.016759,-.014368,
-.016939,-.013695,
-.017,-.013,
0.0*
%
%ADD19MACRO19*%
%AMMACRO57*
4,1,3,-.0125,-.025,
.0125,0.0,
-.0125,.025,
-.0125,-.025,
0.0*
%
%ADD57MACRO57*%
%ADD38C,.04*%
%ADD41C,.032*%
%AMMACRO59*
4,1,40,-.007,-.004,
-.007,.004,
-.00697,.004347,
-.006879,.004684,
-.006732,.005,
-.006532,.005286,
-.006286,.005532,
-.006,.005732,
-.005684,.005879,
-.005347,.00597,
-.005,.006,
.005,.006,
.005347,.00597,
.005684,.005879,
.006,.005732,
.006286,.005532,
.006532,.005286,
.006732,.005,
.006879,.004684,
.00697,.004347,
.007,.004,
.007,-.004,
.00697,-.004347,
.006879,-.004684,
.006732,-.005,
.006532,-.005286,
.006286,-.005532,
.006,-.005732,
.005684,-.005879,
.005347,-.00597,
.005,-.006,
-.005,-.006,
-.005347,-.00597,
-.005684,-.005879,
-.006,-.005732,
-.006286,-.005532,
-.006532,-.005286,
-.006732,-.005,
-.006879,-.004684,
-.00697,-.004347,
-.007,-.004,
0.0*
%
%ADD59MACRO59*%
%ADD22C,.024*%
%AMMACRO53*
4,1,40,-.004,.007,
.004,.007,
.004347,.00697,
.004684,.006879,
.005,.006732,
.005286,.006532,
.005532,.006286,
.005732,.006,
.005879,.005684,
.00597,.005347,
.006,.005,
.006,-.005,
.00597,-.005347,
.005879,-.005684,
.005732,-.006,
.005532,-.006286,
.005286,-.006532,
.005,-.006732,
.004684,-.006879,
.004347,-.00697,
.004,-.007,
-.004,-.007,
-.004347,-.00697,
-.004684,-.006879,
-.005,-.006732,
-.005286,-.006532,
-.005532,-.006286,
-.005732,-.006,
-.005879,-.005684,
-.00597,-.005347,
-.006,-.005,
-.006,.005,
-.00597,.005347,
-.005879,.005684,
-.005732,.006,
-.005532,.006286,
-.005286,.006532,
-.005,.006732,
-.004684,.006879,
-.004347,.00697,
-.004,.007,
0.0*
%
%ADD53MACRO53*%
%ADD39C,.028*%
%AMMACRO50*
4,1,40,.0225,.007,
.022378,.008389,
.022018,.009736,
.021428,.011,
.020628,.012142,
.019642,.013128,
.0185,.013928,
.017236,.014518,
.015889,.014878,
.0145,.015,
-.0145,.015,
-.015889,.014878,
-.017236,.014518,
-.0185,.013928,
-.019642,.013128,
-.020628,.012142,
-.021428,.011,
-.022018,.009736,
-.022378,.008389,
-.0225,.007,
-.0225,-.007,
-.022378,-.008389,
-.022018,-.009736,
-.021428,-.011,
-.020628,-.012142,
-.019642,-.013128,
-.0185,-.013928,
-.017236,-.014518,
-.015889,-.014878,
-.0145,-.015,
.0145,-.015,
.015889,-.014878,
.017236,-.014518,
.0185,-.013928,
.019642,-.013128,
.020628,-.012142,
.021428,-.011,
.022018,-.009736,
.022378,-.008389,
.0225,-.007,
.0225,.007,
0.0*
%
%ADD50MACRO50*%
%AMMACRO49*
4,1,40,.008,.014,
-.008,.014,
-.008695,.013939,
-.009368,.013759,
-.01,.013464,
-.010571,.013064,
-.011064,.012571,
-.011464,.012,
-.011759,.011368,
-.011939,.010695,
-.012,.01,
-.012,-.01,
-.011939,-.010695,
-.011759,-.011368,
-.011464,-.012,
-.011064,-.012571,
-.010571,-.013064,
-.01,-.013464,
-.009368,-.013759,
-.008695,-.013939,
-.008,-.014,
.008,-.014,
.008695,-.013939,
.009368,-.013759,
.01,-.013464,
.010571,-.013064,
.011064,-.012571,
.011464,-.012,
.011759,-.011368,
.011939,-.010695,
.012,-.01,
.012,.01,
.011939,.010695,
.011759,.011368,
.011464,.012,
.011064,.012571,
.010571,.013064,
.01,.013464,
.009368,.013759,
.008695,.013939,
.008,.014,
0.0*
%
%ADD49MACRO49*%
%AMMACRO48*
4,1,40,.014,-.008,
.014,.008,
.013939,.008695,
.013759,.009368,
.013464,.01,
.013064,.010571,
.012571,.011064,
.012,.011464,
.011368,.011759,
.010695,.011939,
.01,.012,
-.01,.012,
-.010695,.011939,
-.011368,.011759,
-.012,.011464,
-.012571,.011064,
-.013064,.010571,
-.013464,.01,
-.013759,.009368,
-.013939,.008695,
-.014,.008,
-.014,-.008,
-.013939,-.008695,
-.013759,-.009368,
-.013464,-.01,
-.013064,-.010571,
-.012571,-.011064,
-.012,-.011464,
-.011368,-.011759,
-.010695,-.011939,
-.01,-.012,
.01,-.012,
.010695,-.011939,
.011368,-.011759,
.012,-.011464,
.012571,-.011064,
.013064,-.010571,
.013464,-.01,
.013759,-.009368,
.013939,-.008695,
.014,-.008,
0.0*
%
%ADD48MACRO48*%
%AMMACRO17*
4,1,40,.007,-.011,
-.007,-.011,
-.007695,-.010939,
-.008368,-.010759,
-.009,-.010464,
-.009571,-.010064,
-.010064,-.009571,
-.010464,-.009,
-.010759,-.008368,
-.010939,-.007695,
-.011,-.007,
-.011,.007,
-.010939,.007695,
-.010759,.008368,
-.010464,.009,
-.010064,.009571,
-.009571,.010064,
-.009,.010464,
-.008368,.010759,
-.007695,.010939,
-.007,.011,
.007,.011,
.007695,.010939,
.008368,.010759,
.009,.010464,
.009571,.010064,
.010064,.009571,
.010464,.009,
.010759,.008368,
.010939,.007695,
.011,.007,
.011,-.007,
.010939,-.007695,
.010759,-.008368,
.010464,-.009,
.010064,-.009571,
.009571,-.010064,
.009,-.010464,
.008368,-.010759,
.007695,-.010939,
.007,-.011,
0.0*
%
%ADD17MACRO17*%
%AMMACRO10*
4,1,40,-.011,-.007,
-.011,.007,
-.010939,.007695,
-.010759,.008368,
-.010464,.009,
-.010064,.009571,
-.009571,.010064,
-.009,.010464,
-.008368,.010759,
-.007695,.010939,
-.007,.011,
.007,.011,
.007695,.010939,
.008368,.010759,
.009,.010464,
.009571,.010064,
.010064,.009571,
.010464,.009,
.010759,.008368,
.010939,.007695,
.011,.007,
.011,-.007,
.010939,-.007695,
.010759,-.008368,
.010464,-.009,
.010064,-.009571,
.009571,-.010064,
.009,-.010464,
.008368,-.010759,
.007695,-.010939,
.007,-.011,
-.007,-.011,
-.007695,-.010939,
-.008368,-.010759,
-.009,-.010464,
-.009571,-.010064,
-.010064,-.009571,
-.010464,-.009,
-.010759,-.008368,
-.010939,-.007695,
-.011,-.007,
0.0*
%
%ADD10MACRO10*%
%AMMACRO30*
4,1,40,-.012,-.008,
-.012,.008,
-.011939,.008695,
-.011759,.009368,
-.011464,.01,
-.011064,.010571,
-.010571,.011064,
-.01,.011464,
-.009368,.011759,
-.008695,.011939,
-.008,.012,
.008,.012,
.008695,.011939,
.009368,.011759,
.01,.011464,
.010571,.011064,
.011064,.010571,
.011464,.01,
.011759,.009368,
.011939,.008695,
.012,.008,
.012,-.008,
.011939,-.008695,
.011759,-.009368,
.011464,-.01,
.011064,-.010571,
.010571,-.011064,
.01,-.011464,
.009368,-.011759,
.008695,-.011939,
.008,-.012,
-.008,-.012,
-.008695,-.011939,
-.009368,-.011759,
-.01,-.011464,
-.010571,-.011064,
-.011064,-.010571,
-.011464,-.01,
-.011759,-.009368,
-.011939,-.008695,
-.012,-.008,
0.0*
%
%ADD30MACRO30*%
%AMMACRO32*
4,1,40,-.008,.012,
.008,.012,
.008695,.011939,
.009368,.011759,
.01,.011464,
.010571,.011064,
.011064,.010571,
.011464,.01,
.011759,.009368,
.011939,.008695,
.012,.008,
.012,-.008,
.011939,-.008695,
.011759,-.009368,
.011464,-.01,
.011064,-.010571,
.010571,-.011064,
.01,-.011464,
.009368,-.011759,
.008695,-.011939,
.008,-.012,
-.008,-.012,
-.008695,-.011939,
-.009368,-.011759,
-.01,-.011464,
-.010571,-.011064,
-.011064,-.010571,
-.011464,-.01,
-.011759,-.009368,
-.011939,-.008695,
-.012,-.008,
-.012,.008,
-.011939,.008695,
-.011759,.009368,
-.011464,.01,
-.011064,.010571,
-.010571,.011064,
-.01,.011464,
-.009368,.011759,
-.008695,.011939,
-.008,.012,
0.0*
%
%ADD32MACRO32*%
%AMMACRO34*
4,1,40,-.013,.017,
.013,.017,
.013695,.016939,
.014368,.016759,
.015,.016464,
.015571,.016064,
.016064,.015571,
.016464,.015,
.016759,.014368,
.016939,.013695,
.017,.013,
.017,-.013,
.016939,-.013695,
.016759,-.014368,
.016464,-.015,
.016064,-.015571,
.015571,-.016064,
.015,-.016464,
.014368,-.016759,
.013695,-.016939,
.013,-.017,
-.013,-.017,
-.013695,-.016939,
-.014368,-.016759,
-.015,-.016464,
-.015571,-.016064,
-.016064,-.015571,
-.016464,-.015,
-.016759,-.014368,
-.016939,-.013695,
-.017,-.013,
-.017,.013,
-.016939,.013695,
-.016759,.014368,
-.016464,.015,
-.016064,.015571,
-.015571,.016064,
-.015,.016464,
-.014368,.016759,
-.013695,.016939,
-.013,.017,
0.0*
%
%ADD34MACRO34*%
%AMMACRO36*
4,1,40,.017,.013,
.017,-.013,
.016939,-.013695,
.016759,-.014368,
.016464,-.015,
.016064,-.015571,
.015571,-.016064,
.015,-.016464,
.014368,-.016759,
.013695,-.016939,
.013,-.017,
-.013,-.017,
-.013695,-.016939,
-.014368,-.016759,
-.015,-.016464,
-.015571,-.016064,
-.016064,-.015571,
-.016464,-.015,
-.016759,-.014368,
-.016939,-.013695,
-.017,-.013,
-.017,.013,
-.016939,.013695,
-.016759,.014368,
-.016464,.015,
-.016064,.015571,
-.015571,.016064,
-.015,.016464,
-.014368,.016759,
-.013695,.016939,
-.013,.017,
.013,.017,
.013695,.016939,
.014368,.016759,
.015,.016464,
.015571,.016064,
.016064,.015571,
.016464,.015,
.016759,.014368,
.016939,.013695,
.017,.013,
0.0*
%
%ADD36MACRO36*%
%AMMACRO27*
4,1,40,.007,-.011,
-.007,-.011,
-.007695,-.010939,
-.008368,-.010759,
-.009,-.010464,
-.009571,-.010064,
-.010064,-.009571,
-.010464,-.009,
-.010759,-.008368,
-.010939,-.007695,
-.011,-.007,
-.011,.007,
-.010939,.007695,
-.010759,.008368,
-.010464,.009,
-.010064,.009571,
-.009571,.010064,
-.009,.010464,
-.008368,.010759,
-.007695,.010939,
-.007,.011,
.007,.011,
.007695,.010939,
.008368,.010759,
.009,.010464,
.009571,.010064,
.010064,.009571,
.010464,.009,
.010759,.008368,
.010939,.007695,
.011,.007,
.011,-.007,
.010939,-.007695,
.010759,-.008368,
.010464,-.009,
.010064,-.009571,
.009571,-.010064,
.009,-.010464,
.008368,-.010759,
.007695,-.010939,
.007,-.011,
0.0*
%
%ADD27MACRO27*%
%AMMACRO11*
4,1,40,-.011,-.007,
-.011,.007,
-.010939,.007695,
-.010759,.008368,
-.010464,.009,
-.010064,.009571,
-.009571,.010064,
-.009,.010464,
-.008368,.010759,
-.007695,.010939,
-.007,.011,
.007,.011,
.007695,.010939,
.008368,.010759,
.009,.010464,
.009571,.010064,
.010064,.009571,
.010464,.009,
.010759,.008368,
.010939,.007695,
.011,.007,
.011,-.007,
.010939,-.007695,
.010759,-.008368,
.010464,-.009,
.010064,-.009571,
.009571,-.010064,
.009,-.010464,
.008368,-.010759,
.007695,-.010939,
.007,-.011,
-.007,-.011,
-.007695,-.010939,
-.008368,-.010759,
-.009,-.010464,
-.009571,-.010064,
-.010064,-.009571,
-.010464,-.009,
-.010759,-.008368,
-.010939,-.007695,
-.011,-.007,
0.0*
%
%ADD11MACRO11*%
%AMMACRO29*
4,1,40,-.012,-.008,
-.012,.008,
-.011939,.008695,
-.011759,.009368,
-.011464,.01,
-.011064,.010571,
-.010571,.011064,
-.01,.011464,
-.009368,.011759,
-.008695,.011939,
-.008,.012,
.008,.012,
.008695,.011939,
.009368,.011759,
.01,.011464,
.010571,.011064,
.011064,.010571,
.011464,.01,
.011759,.009368,
.011939,.008695,
.012,.008,
.012,-.008,
.011939,-.008695,
.011759,-.009368,
.011464,-.01,
.011064,-.010571,
.010571,-.011064,
.01,-.011464,
.009368,-.011759,
.008695,-.011939,
.008,-.012,
-.008,-.012,
-.008695,-.011939,
-.009368,-.011759,
-.01,-.011464,
-.010571,-.011064,
-.011064,-.010571,
-.011464,-.01,
-.011759,-.009368,
-.011939,-.008695,
-.012,-.008,
0.0*
%
%ADD29MACRO29*%
%AMMACRO31*
4,1,40,-.008,.012,
.008,.012,
.008695,.011939,
.009368,.011759,
.01,.011464,
.010571,.011064,
.011064,.010571,
.011464,.01,
.011759,.009368,
.011939,.008695,
.012,.008,
.012,-.008,
.011939,-.008695,
.011759,-.009368,
.011464,-.01,
.011064,-.010571,
.010571,-.011064,
.01,-.011464,
.009368,-.011759,
.008695,-.011939,
.008,-.012,
-.008,-.012,
-.008695,-.011939,
-.009368,-.011759,
-.01,-.011464,
-.010571,-.011064,
-.011064,-.010571,
-.011464,-.01,
-.011759,-.009368,
-.011939,-.008695,
-.012,-.008,
-.012,.008,
-.011939,.008695,
-.011759,.009368,
-.011464,.01,
-.011064,.010571,
-.010571,.011064,
-.01,.011464,
-.009368,.011759,
-.008695,.011939,
-.008,.012,
0.0*
%
%ADD31MACRO31*%
%AMMACRO35*
4,1,40,-.013,.017,
.013,.017,
.013695,.016939,
.014368,.016759,
.015,.016464,
.015571,.016064,
.016064,.015571,
.016464,.015,
.016759,.014368,
.016939,.013695,
.017,.013,
.017,-.013,
.016939,-.013695,
.016759,-.014368,
.016464,-.015,
.016064,-.015571,
.015571,-.016064,
.015,-.016464,
.014368,-.016759,
.013695,-.016939,
.013,-.017,
-.013,-.017,
-.013695,-.016939,
-.014368,-.016759,
-.015,-.016464,
-.015571,-.016064,
-.016064,-.015571,
-.016464,-.015,
-.016759,-.014368,
-.016939,-.013695,
-.017,-.013,
-.017,.013,
-.016939,.013695,
-.016759,.014368,
-.016464,.015,
-.016064,.015571,
-.015571,.016064,
-.015,.016464,
-.014368,.016759,
-.013695,.016939,
-.013,.017,
0.0*
%
%ADD35MACRO35*%
%AMMACRO37*
4,1,40,.017,.013,
.017,-.013,
.016939,-.013695,
.016759,-.014368,
.016464,-.015,
.016064,-.015571,
.015571,-.016064,
.015,-.016464,
.014368,-.016759,
.013695,-.016939,
.013,-.017,
-.013,-.017,
-.013695,-.016939,
-.014368,-.016759,
-.015,-.016464,
-.015571,-.016064,
-.016064,-.015571,
-.016464,-.015,
-.016759,-.014368,
-.016939,-.013695,
-.017,-.013,
-.017,.013,
-.016939,.013695,
-.016759,.014368,
-.016464,.015,
-.016064,.015571,
-.015571,.016064,
-.015,.016464,
-.014368,.016759,
-.013695,.016939,
-.013,.017,
.013,.017,
.013695,.016939,
.014368,.016759,
.015,.016464,
.015571,.016064,
.016064,.015571,
.016464,.015,
.016759,.014368,
.016939,.013695,
.017,.013,
0.0*
%
%ADD37MACRO37*%
%AMMACRO60*
4,1,3,-.0125,0.0,
.0125,-.025,
.0125,.025,
-.0125,0.0,
0.0*
%
%ADD60MACRO60*%
%ADD54R,.012X.06*%
%ADD51R,.016X.02*%
%ADD40R,.06X.014*%
%AMMACRO58*
4,1,40,.007,.004,
.007,-.004,
.00697,-.004347,
.006879,-.004684,
.006732,-.005,
.006532,-.005286,
.006286,-.005532,
.006,-.005732,
.005684,-.005879,
.005347,-.00597,
.005,-.006,
-.005,-.006,
-.005347,-.00597,
-.005684,-.005879,
-.006,-.005732,
-.006286,-.005532,
-.006532,-.005286,
-.006732,-.005,
-.006879,-.004684,
-.00697,-.004347,
-.007,-.004,
-.007,.004,
-.00697,.004347,
-.006879,.004684,
-.006732,.005,
-.006532,.005286,
-.006286,.005532,
-.006,.005732,
-.005684,.005879,
-.005347,.00597,
-.005,.006,
.005,.006,
.005347,.00597,
.005684,.005879,
.006,.005732,
.006286,.005532,
.006532,.005286,
.006732,.005,
.006879,.004684,
.00697,.004347,
.007,.004,
0.0*
%
%ADD58MACRO58*%
%AMMACRO55*
4,1,40,.004,-.007,
-.004,-.007,
-.004347,-.00697,
-.004684,-.006879,
-.005,-.006732,
-.005286,-.006532,
-.005532,-.006286,
-.005732,-.006,
-.005879,-.005684,
-.00597,-.005347,
-.006,-.005,
-.006,.005,
-.00597,.005347,
-.005879,.005684,
-.005732,.006,
-.005532,.006286,
-.005286,.006532,
-.005,.006732,
-.004684,.006879,
-.004347,.00697,
-.004,.007,
.004,.007,
.004347,.00697,
.004684,.006879,
.005,.006732,
.005286,.006532,
.005532,.006286,
.005732,.006,
.005879,.005684,
.00597,.005347,
.006,.005,
.006,-.005,
.00597,-.005347,
.005879,-.005684,
.005732,-.006,
.005532,-.006286,
.005286,-.006532,
.005,-.006732,
.004684,-.006879,
.004347,-.00697,
.004,-.007,
0.0*
%
%ADD55MACRO55*%
%ADD45R,.05X.065*%
%ADD56R,.065X.05*%
%ADD28R,.048X.016*%
%ADD16R,.045X.055*%
%ADD43R,.016X.048*%
%ADD33R,.055X.045*%
%ADD52R,.063X.039*%
%AMMACRO47*
4,1,40,-.014,.008,
-.014,-.008,
-.013939,-.008695,
-.013759,-.009368,
-.013464,-.01,
-.013064,-.010571,
-.012571,-.011064,
-.012,-.011464,
-.011368,-.011759,
-.010695,-.011939,
-.01,-.012,
.01,-.012,
.010695,-.011939,
.011368,-.011759,
.012,-.011464,
.012571,-.011064,
.013064,-.010571,
.013464,-.01,
.013759,-.009368,
.013939,-.008695,
.014,-.008,
.014,.008,
.013939,.008695,
.013759,.009368,
.013464,.01,
.013064,.010571,
.012571,.011064,
.012,.011464,
.011368,.011759,
.010695,.011939,
.01,.012,
-.01,.012,
-.010695,.011939,
-.011368,.011759,
-.012,.011464,
-.012571,.011064,
-.013064,.010571,
-.013464,.01,
-.013759,.009368,
-.013939,.008695,
-.014,.008,
0.0*
%
%ADD47MACRO47*%
%AMMACRO46*
4,1,40,-.0225,-.007,
-.022378,-.008389,
-.022018,-.009736,
-.021428,-.011,
-.020628,-.012142,
-.019642,-.013128,
-.0185,-.013928,
-.017236,-.014518,
-.015889,-.014878,
-.0145,-.015,
.0145,-.015,
.015889,-.014878,
.017236,-.014518,
.0185,-.013928,
.019642,-.013128,
.020628,-.012142,
.021428,-.011,
.022018,-.009736,
.022378,-.008389,
.0225,-.007,
.0225,.007,
.022378,.008389,
.022018,.009736,
.021428,.011,
.020628,.012142,
.019642,.013128,
.0185,.013928,
.017236,.014518,
.015889,.014878,
.0145,.015,
-.0145,.015,
-.015889,.014878,
-.017236,.014518,
-.0185,.013928,
-.019642,.013128,
-.020628,.012142,
-.021428,.011,
-.022018,.009736,
-.022378,.008389,
-.0225,.007,
-.0225,-.007,
0.0*
%
%ADD46MACRO46*%
%AMMACRO44*
4,1,40,-.007,.0225,
-.008389,.022378,
-.009736,.022018,
-.011,.021428,
-.012142,.020628,
-.013128,.019642,
-.013928,.0185,
-.014518,.017236,
-.014878,.015889,
-.015,.0145,
-.015,-.0145,
-.014878,-.015889,
-.014518,-.017236,
-.013928,-.0185,
-.013128,-.019642,
-.012142,-.020628,
-.011,-.021428,
-.009736,-.022018,
-.008389,-.022378,
-.007,-.0225,
.007,-.0225,
.008389,-.022378,
.009736,-.022018,
.011,-.021428,
.012142,-.020628,
.013128,-.019642,
.013928,-.0185,
.014518,-.017236,
.014878,-.015889,
.015,-.0145,
.015,.0145,
.014878,.015889,
.014518,.017236,
.013928,.0185,
.013128,.019642,
.012142,.020628,
.011,.021428,
.009736,.022018,
.008389,.022378,
.007,.0225,
-.007,.0225,
0.0*
%
%ADD44MACRO44*%
%AMMACRO24*
4,1,40,.012,.008,
.012,-.008,
.011939,-.008695,
.011759,-.009368,
.011464,-.01,
.011064,-.010571,
.010571,-.011064,
.01,-.011464,
.009368,-.011759,
.008695,-.011939,
.008,-.012,
-.008,-.012,
-.008695,-.011939,
-.009368,-.011759,
-.01,-.011464,
-.010571,-.011064,
-.011064,-.010571,
-.011464,-.01,
-.011759,-.009368,
-.011939,-.008695,
-.012,-.008,
-.012,.008,
-.011939,.008695,
-.011759,.009368,
-.011464,.01,
-.011064,.010571,
-.010571,.011064,
-.01,.011464,
-.009368,.011759,
-.008695,.011939,
-.008,.012,
.008,.012,
.008695,.011939,
.009368,.011759,
.01,.011464,
.010571,.011064,
.011064,.010571,
.011464,.01,
.011759,.009368,
.011939,.008695,
.012,.008,
0.0*
%
%ADD24MACRO24*%
%AMMACRO15*
4,1,40,.008,-.012,
-.008,-.012,
-.008695,-.011939,
-.009368,-.011759,
-.01,-.011464,
-.010571,-.011064,
-.011064,-.010571,
-.011464,-.01,
-.011759,-.009368,
-.011939,-.008695,
-.012,-.008,
-.012,.008,
-.011939,.008695,
-.011759,.009368,
-.011464,.01,
-.011064,.010571,
-.010571,.011064,
-.01,.011464,
-.009368,.011759,
-.008695,.011939,
-.008,.012,
.008,.012,
.008695,.011939,
.009368,.011759,
.01,.011464,
.010571,.011064,
.011064,.010571,
.011464,.01,
.011759,.009368,
.011939,.008695,
.012,.008,
.012,-.008,
.011939,-.008695,
.011759,-.009368,
.011464,-.01,
.011064,-.010571,
.010571,-.011064,
.01,-.011464,
.009368,-.011759,
.008695,-.011939,
.008,-.012,
0.0*
%
%ADD15MACRO15*%
%AMMACRO12*
4,1,40,-.007,.011,
.007,.011,
.007695,.010939,
.008368,.010759,
.009,.010464,
.009571,.010064,
.010064,.009571,
.010464,.009,
.010759,.008368,
.010939,.007695,
.011,.007,
.011,-.007,
.010939,-.007695,
.010759,-.008368,
.010464,-.009,
.010064,-.009571,
.009571,-.010064,
.009,-.010464,
.008368,-.010759,
.007695,-.010939,
.007,-.011,
-.007,-.011,
-.007695,-.010939,
-.008368,-.010759,
-.009,-.010464,
-.009571,-.010064,
-.010064,-.009571,
-.010464,-.009,
-.010759,-.008368,
-.010939,-.007695,
-.011,-.007,
-.011,.007,
-.010939,.007695,
-.010759,.008368,
-.010464,.009,
-.010064,.009571,
-.009571,.010064,
-.009,.010464,
-.008368,.010759,
-.007695,.010939,
-.007,.011,
0.0*
%
%ADD12MACRO12*%
%AMMACRO25*
4,1,40,.011,.007,
.011,-.007,
.010939,-.007695,
.010759,-.008368,
.010464,-.009,
.010064,-.009571,
.009571,-.010064,
.009,-.010464,
.008368,-.010759,
.007695,-.010939,
.007,-.011,
-.007,-.011,
-.007695,-.010939,
-.008368,-.010759,
-.009,-.010464,
-.009571,-.010064,
-.010064,-.009571,
-.010464,-.009,
-.010759,-.008368,
-.010939,-.007695,
-.011,-.007,
-.011,.007,
-.010939,.007695,
-.010759,.008368,
-.010464,.009,
-.010064,.009571,
-.009571,.010064,
-.009,.010464,
-.008368,.010759,
-.007695,.010939,
-.007,.011,
.007,.011,
.007695,.010939,
.008368,.010759,
.009,.010464,
.009571,.010064,
.010064,.009571,
.010464,.009,
.010759,.008368,
.010939,.007695,
.011,.007,
0.0*
%
%ADD25MACRO25*%
%AMMACRO20*
4,1,40,.013,-.017,
-.013,-.017,
-.013695,-.016939,
-.014368,-.016759,
-.015,-.016464,
-.015571,-.016064,
-.016064,-.015571,
-.016464,-.015,
-.016759,-.014368,
-.016939,-.013695,
-.017,-.013,
-.017,.013,
-.016939,.013695,
-.016759,.014368,
-.016464,.015,
-.016064,.015571,
-.015571,.016064,
-.015,.016464,
-.014368,.016759,
-.013695,.016939,
-.013,.017,
.013,.017,
.013695,.016939,
.014368,.016759,
.015,.016464,
.015571,.016064,
.016064,.015571,
.016464,.015,
.016759,.014368,
.016939,.013695,
.017,.013,
.017,-.013,
.016939,-.013695,
.016759,-.014368,
.016464,-.015,
.016064,-.015571,
.015571,-.016064,
.015,-.016464,
.014368,-.016759,
.013695,-.016939,
.013,-.017,
0.0*
%
%ADD20MACRO20*%
%AMMACRO18*
4,1,40,-.017,-.013,
-.017,.013,
-.016939,.013695,
-.016759,.014368,
-.016464,.015,
-.016064,.015571,
-.015571,.016064,
-.015,.016464,
-.014368,.016759,
-.013695,.016939,
-.013,.017,
.013,.017,
.013695,.016939,
.014368,.016759,
.015,.016464,
.015571,.016064,
.016064,.015571,
.016464,.015,
.016759,.014368,
.016939,.013695,
.017,.013,
.017,-.013,
.016939,-.013695,
.016759,-.014368,
.016464,-.015,
.016064,-.015571,
.015571,-.016064,
.015,-.016464,
.014368,-.016759,
.013695,-.016939,
.013,-.017,
-.013,-.017,
-.013695,-.016939,
-.014368,-.016759,
-.015,-.016464,
-.015571,-.016064,
-.016064,-.015571,
-.016464,-.015,
-.016759,-.014368,
-.016939,-.013695,
-.017,-.013,
0.0*
%
%ADD18MACRO18*%
%AMMACRO23*
4,1,40,.012,.008,
.012,-.008,
.011939,-.008695,
.011759,-.009368,
.011464,-.01,
.011064,-.010571,
.010571,-.011064,
.01,-.011464,
.009368,-.011759,
.008695,-.011939,
.008,-.012,
-.008,-.012,
-.008695,-.011939,
-.009368,-.011759,
-.01,-.011464,
-.010571,-.011064,
-.011064,-.010571,
-.011464,-.01,
-.011759,-.009368,
-.011939,-.008695,
-.012,-.008,
-.012,.008,
-.011939,.008695,
-.011759,.009368,
-.011464,.01,
-.011064,.010571,
-.010571,.011064,
-.01,.011464,
-.009368,.011759,
-.008695,.011939,
-.008,.012,
.008,.012,
.008695,.011939,
.009368,.011759,
.01,.011464,
.010571,.011064,
.011064,.010571,
.011464,.01,
.011759,.009368,
.011939,.008695,
.012,.008,
0.0*
%
%ADD23MACRO23*%
%AMMACRO14*
4,1,40,.008,-.012,
-.008,-.012,
-.008695,-.011939,
-.009368,-.011759,
-.01,-.011464,
-.010571,-.011064,
-.011064,-.010571,
-.011464,-.01,
-.011759,-.009368,
-.011939,-.008695,
-.012,-.008,
-.012,.008,
-.011939,.008695,
-.011759,.009368,
-.011464,.01,
-.011064,.010571,
-.010571,.011064,
-.01,.011464,
-.009368,.011759,
-.008695,.011939,
-.008,.012,
.008,.012,
.008695,.011939,
.009368,.011759,
.01,.011464,
.010571,.011064,
.011064,.010571,
.011464,.01,
.011759,.009368,
.011939,.008695,
.012,.008,
.012,-.008,
.011939,-.008695,
.011759,-.009368,
.011464,-.01,
.011064,-.010571,
.010571,-.011064,
.01,-.011464,
.009368,-.011759,
.008695,-.011939,
.008,-.012,
0.0*
%
%ADD14MACRO14*%
%AMMACRO13*
4,1,40,-.007,.011,
.007,.011,
.007695,.010939,
.008368,.010759,
.009,.010464,
.009571,.010064,
.010064,.009571,
.010464,.009,
.010759,.008368,
.010939,.007695,
.011,.007,
.011,-.007,
.010939,-.007695,
.010759,-.008368,
.010464,-.009,
.010064,-.009571,
.009571,-.010064,
.009,-.010464,
.008368,-.010759,
.007695,-.010939,
.007,-.011,
-.007,-.011,
-.007695,-.010939,
-.008368,-.010759,
-.009,-.010464,
-.009571,-.010064,
-.010064,-.009571,
-.010464,-.009,
-.010759,-.008368,
-.010939,-.007695,
-.011,-.007,
-.011,.007,
-.010939,.007695,
-.010759,.008368,
-.010464,.009,
-.010064,.009571,
-.009571,.010064,
-.009,.010464,
-.008368,.010759,
-.007695,.010939,
-.007,.011,
0.0*
%
%ADD13MACRO13*%
%ADD61C,.02*%
%ADD62C,.006*%
G75*
%LPD*%
G75*
G54D10*
X75373Y509879D03*
X75405Y517477D03*
X69878Y509777D03*
X69778Y517477D03*
X64251Y509877D03*
X64151Y517477D03*
X97900Y510000D03*
X92286Y517477D03*
X81032D03*
X97913D03*
X92273Y510000D03*
X81068Y509866D03*
X86673Y510000D03*
X86659Y517477D03*
X136702Y492561D03*
X127800Y618100D03*
X174900Y506500D03*
X191869Y506489D03*
X167000Y520500D03*
X199892Y503022D03*
X162800Y494300D03*
X162700Y520500D03*
X171200Y525800D03*
X186111Y520181D03*
X182600Y536000D03*
X145400D03*
X198600Y536200D03*
X186900Y536100D03*
X178600Y535800D03*
X174500D03*
X159300Y529700D03*
X156501Y564267D03*
X196890Y567300D03*
X200910Y563190D03*
X150067Y614143D03*
X266800Y575100D03*
X270947Y576404D03*
X228400Y567750D03*
X238100Y586400D03*
X215100Y536000D03*
X242100Y586400D03*
X219200Y536500D03*
X232500Y529200D03*
X242000Y594200D03*
X327174Y389318D03*
X310700Y562600D03*
X315290Y681870D03*
X349182Y381274D03*
X345244Y587260D03*
X369500Y576100D03*
X351900Y532300D03*
X380000Y601800D03*
X634000Y194200D03*
X730900Y194700D03*
X670200Y203300D03*
X768529Y199354D03*
X740100Y491484D03*
X735600D03*
X744600D03*
X806100Y225900D03*
X802100D03*
X818100D03*
X814100D03*
X810100D03*
G54D20*
X49250Y580250D03*
X41868Y567316D03*
X96900Y712200D03*
X190450Y559250D03*
X194459Y577497D03*
X197030Y583440D03*
X185130Y552000D03*
X174460Y615380D03*
X694099Y607558D03*
X757500Y185200D03*
X789237Y202518D03*
X775000Y202500D03*
X803562Y202483D03*
G54D11*
X75373Y506479D03*
X75405Y514077D03*
X69878Y506377D03*
X69778Y514077D03*
X64251Y506477D03*
X64151Y514077D03*
X97900Y506600D03*
X92286Y514077D03*
X81032D03*
X97913D03*
X92273Y506600D03*
X81068Y506466D03*
X86673Y506600D03*
X86659Y514077D03*
X136702Y489161D03*
X127800Y614700D03*
X174900Y503100D03*
X191869Y503089D03*
X167000Y517100D03*
X199892Y499622D03*
X162800Y490900D03*
X162700Y517100D03*
X171200Y522400D03*
X159300Y526300D03*
X186111Y516781D03*
X182600Y532600D03*
X145400D03*
X198600Y532800D03*
X186900Y532700D03*
X178600Y532400D03*
X174500D03*
X156501Y560867D03*
X196890Y563900D03*
X200910Y559790D03*
X150067Y610743D03*
X232500Y525800D03*
X266800Y571700D03*
X270947Y573004D03*
X228400Y564350D03*
X238100Y583000D03*
X242000Y590800D03*
X215100Y532600D03*
X242100Y583000D03*
X219200Y533100D03*
X327174Y385918D03*
X310700Y559200D03*
X315290Y678470D03*
X349182Y377874D03*
X345244Y583860D03*
X369500Y572700D03*
X351900Y528900D03*
X380000Y598400D03*
X634000Y190800D03*
X670200Y199900D03*
X730900Y191300D03*
X768529Y195954D03*
X740100Y488084D03*
X735600D03*
X744600D03*
X806100Y222500D03*
X802100D03*
X818100D03*
X814100D03*
X810100D03*
G54D12*
X49306Y526995D03*
X41875D03*
X49306Y521269D03*
X41832Y521271D03*
X58500Y575850D03*
X54156Y571795D03*
X49306Y532622D03*
X41865Y532638D03*
X49385Y555153D03*
X41885D03*
X49306Y538249D03*
X41758Y538254D03*
X49306Y543876D03*
X41858Y543881D03*
X49385Y549526D03*
X41903Y549508D03*
X49385Y560879D03*
X41800Y560900D03*
X129170Y499350D03*
X130492Y602854D03*
X167000Y527700D03*
X153115Y464338D03*
Y472738D03*
X197715Y471838D03*
X153015Y476938D03*
X197815Y475938D03*
X175487Y587147D03*
X205440Y624780D03*
X185300Y635300D03*
X163900Y606760D03*
X207100Y641270D03*
X206600Y653100D03*
X200450Y607600D03*
X172902Y629826D03*
X215220Y491100D03*
X242000Y575100D03*
X241900Y558500D03*
X249700Y565900D03*
X241900Y550400D03*
X249717Y569957D03*
X269309Y587813D03*
X241900Y554400D03*
X241700Y562600D03*
Y566700D03*
X242000Y571000D03*
X249732Y579067D03*
X227548Y581666D03*
X243600Y539000D03*
X215200Y634500D03*
X225508Y637894D03*
X214508Y653294D03*
X334700Y512000D03*
X377200Y31000D03*
X374484Y626032D03*
X357000Y683400D03*
X347500Y687500D03*
X370500Y671900D03*
X457400Y33600D03*
X459900Y61900D03*
X441400Y37800D03*
X493194Y34455D03*
X713773Y253883D03*
X712379Y257964D03*
X689000Y265100D03*
X728530Y287930D03*
X689000Y269200D03*
X673400Y307400D03*
X779600Y182200D03*
X793473Y182318D03*
X764700Y180800D03*
X786390Y249880D03*
X807892Y182209D03*
X815628Y253664D03*
X817900Y314600D03*
G54D30*
X103730Y576452D03*
X175569Y579940D03*
X204770Y552500D03*
X187720Y611240D03*
X225619Y634188D03*
X219320Y605070D03*
X215300Y638400D03*
X214700Y649500D03*
X325300Y681900D03*
X391400Y700700D03*
X371800Y689500D03*
X613300Y358900D03*
X726450Y256550D03*
X726150Y231460D03*
X726360Y225060D03*
X726300Y262300D03*
X733970Y227400D03*
X733960Y230840D03*
X726740Y249850D03*
X726970Y243700D03*
X726429Y237714D03*
X730950Y284210D03*
X726663Y268702D03*
X728700Y275200D03*
X746650Y249900D03*
X775100Y233900D03*
X765900Y262250D03*
X781000Y214700D03*
X741900Y218800D03*
X749400D03*
X781000Y218100D03*
X788519Y218074D03*
X764500Y269000D03*
X749768Y294464D03*
X736120Y288150D03*
X743660Y287810D03*
X804400Y246800D03*
G54D21*
X54850Y580250D03*
X47468Y567316D03*
X102500Y712200D03*
X196050Y559250D03*
X200059Y577497D03*
X202630Y583440D03*
X190730Y552000D03*
X180060Y615380D03*
X699699Y607558D03*
X763100Y185200D03*
X794837Y202518D03*
X780600Y202500D03*
X809162Y202483D03*
G54D13*
X45906Y526995D03*
X38475D03*
X45906Y521269D03*
X38432Y521271D03*
X55100Y575850D03*
X50756Y571795D03*
X45906Y532622D03*
X38465Y532638D03*
X45985Y555153D03*
X38485D03*
X45906Y538249D03*
X38358Y538254D03*
X45906Y543876D03*
X38458Y543881D03*
X45985Y549526D03*
X38503Y549508D03*
X45985Y560879D03*
X38400Y560900D03*
X125770Y499350D03*
X127092Y602854D03*
X163600Y527700D03*
X149715Y464338D03*
Y472738D03*
X194315Y471838D03*
X149615Y476938D03*
X194415Y475938D03*
X172087Y587147D03*
X202040Y624780D03*
X181900Y635300D03*
X160500Y606760D03*
X203700Y641270D03*
X203200Y653100D03*
X197050Y607600D03*
X169502Y629826D03*
X211820Y491100D03*
X238600Y575100D03*
X238500Y558500D03*
X246300Y565900D03*
X238500Y550400D03*
X246317Y569957D03*
X265909Y587813D03*
X238500Y554400D03*
X238300Y562600D03*
Y566700D03*
X238600Y571000D03*
X246332Y579067D03*
X224148Y581666D03*
X240200Y539000D03*
X211800Y634500D03*
X222108Y637894D03*
X211108Y653294D03*
X331300Y512000D03*
X373800Y31000D03*
X371084Y626032D03*
X353600Y683400D03*
X344100Y687500D03*
X367100Y671900D03*
X454000Y33600D03*
X456500Y61900D03*
X438000Y37800D03*
X489794Y34455D03*
X710373Y253883D03*
X708979Y257964D03*
X685600Y265100D03*
X725130Y287930D03*
X685600Y269200D03*
X670000Y307400D03*
X776200Y182200D03*
X790073Y182318D03*
X761300Y180800D03*
X782990Y249880D03*
X804492Y182209D03*
X812228Y253664D03*
X814500Y314600D03*
G54D40*
X165382Y475793D03*
Y473233D03*
Y470673D03*
Y468113D03*
X181562D03*
Y470673D03*
Y473233D03*
Y475793D03*
X326300Y675780D03*
Y673220D03*
Y670660D03*
Y668100D03*
Y665540D03*
Y662980D03*
Y660420D03*
X348500D03*
Y662980D03*
Y665540D03*
Y668100D03*
Y670660D03*
Y673220D03*
Y675780D03*
G54D31*
X96287Y576499D03*
X307900Y514300D03*
X356600Y524400D03*
X356480Y590440D03*
X378500Y578300D03*
X647500Y203400D03*
X648698Y299889D03*
X799200Y218150D03*
X795719Y218124D03*
X797099Y243345D03*
X796829Y234125D03*
X792269Y218094D03*
X764900Y213800D03*
X768479Y212264D03*
X759000Y214700D03*
X806210Y218140D03*
X802650Y218130D03*
G54D22*
X74400Y556700D03*
X141107Y484000D03*
X132899Y489111D03*
X126950Y495528D03*
X108492Y541947D03*
X138350Y584250D03*
X130400Y539899D03*
X126780Y562772D03*
X117121Y579998D03*
X134700Y604000D03*
X118998Y701124D03*
X115598Y708228D03*
X109478Y713245D03*
X171492Y496413D03*
X190416Y498361D03*
X202190Y471014D03*
X202271Y475938D03*
X162530Y500950D03*
X171571Y487041D03*
X176800Y495900D03*
X175700Y521000D03*
X199881Y507507D03*
X188065Y523962D03*
X203065Y493980D03*
X158000Y476938D03*
X157800Y471800D03*
X158200Y467100D03*
X189500Y471900D03*
X190200Y476000D03*
X154660Y510100D03*
X195900Y503600D03*
X153938Y526490D03*
X190603Y519531D03*
X152332Y583318D03*
X191100Y539700D03*
X180540Y539941D03*
X187600Y542450D03*
X203900Y542626D03*
X145150Y540250D03*
X175545Y539699D03*
X165085Y532153D03*
X169200Y534900D03*
X159327Y539484D03*
X152170Y593440D03*
X156501Y567965D03*
X194942Y536499D03*
X199700Y541100D03*
X206700Y539600D03*
X149093Y541418D03*
X197198Y595513D03*
X196500Y603912D03*
X197300Y616100D03*
X198086Y624715D03*
X177378Y637409D03*
X150790Y598540D03*
X163300Y602600D03*
X156669Y604185D03*
X153720Y614010D03*
X207569Y629750D03*
X201000Y603600D03*
X145710Y596640D03*
X185246Y603254D03*
X148000Y606650D03*
X184300Y594500D03*
X162098Y697235D03*
X155846Y723282D03*
X228700Y450600D03*
X238500Y448250D03*
X222508Y479092D03*
X241947Y514306D03*
X219800Y490550D03*
X268448Y520801D03*
X233400Y560600D03*
X233100Y569900D03*
X262911Y568331D03*
X262603Y564342D03*
X233400Y579300D03*
X234722Y574814D03*
X224359Y562475D03*
X225530Y537192D03*
X253700Y531240D03*
X232536Y588078D03*
X235700Y593300D03*
X237775Y545900D03*
X212000Y539600D03*
X265700Y580209D03*
X247000Y574567D03*
X253400Y571400D03*
X231000Y536584D03*
X238000Y532500D03*
X235772Y542321D03*
X212000Y608700D03*
X216000Y626900D03*
X218000Y630400D03*
X249700Y613590D03*
X213161Y623100D03*
X240900Y635200D03*
X227900Y606900D03*
X218968Y600635D03*
X215519Y594866D03*
X231066Y602763D03*
X253583Y653829D03*
X233100Y623400D03*
X256788Y697212D03*
X249090Y676611D03*
X259000Y672225D03*
X334200Y241900D03*
X312300Y247900D03*
X325147Y252424D03*
X313077Y257074D03*
X311464Y381211D03*
X339900Y454200D03*
X332816Y425682D03*
X339269Y407733D03*
X302175Y521026D03*
X314370Y520789D03*
X327600Y515900D03*
X301653Y572452D03*
X322858Y560820D03*
X288700Y586900D03*
X322794Y568615D03*
X285564Y582990D03*
X315500Y563050D03*
Y568700D03*
X340538Y563970D03*
X338200Y558000D03*
X322423Y549010D03*
X315600Y557700D03*
X327300Y655300D03*
X323191Y618260D03*
X333600Y628023D03*
X333338Y696953D03*
X319950Y662500D03*
X303900Y661300D03*
X314250Y662600D03*
X303800Y681682D03*
X360600Y22300D03*
X365900Y67100D03*
X385673Y424903D03*
X389151Y436223D03*
X364577Y425023D03*
X352111Y517737D03*
X373383Y511449D03*
X360300Y590390D03*
X344066Y579700D03*
X358100Y572200D03*
X356300Y549100D03*
X360500Y566200D03*
X377635Y616107D03*
X378800Y624850D03*
X342600Y682800D03*
X388017Y660594D03*
X362900Y683800D03*
X349190Y682490D03*
X377199Y699873D03*
X347010Y692076D03*
X341500Y707000D03*
X362700Y671900D03*
X458500Y27000D03*
X443500Y42000D03*
X439288Y46921D03*
X459700Y66000D03*
X436154Y72470D03*
X508100Y50100D03*
X495500Y61115D03*
X502930Y64170D03*
X489691Y42317D03*
X481093Y67669D03*
X494800Y74100D03*
X544814Y62686D03*
X627930Y198500D03*
X657603Y294530D03*
X652465Y294735D03*
X626988Y367660D03*
X604000Y501806D03*
X627408Y553791D03*
X640400Y557600D03*
X648800Y546000D03*
X715775Y261939D03*
X714226Y249665D03*
X695697Y269200D03*
X701654Y267100D03*
X693277Y313344D03*
X686714Y298448D03*
X695200Y301800D03*
X720900Y434172D03*
X734300Y496000D03*
X716442Y560260D03*
X699472Y560300D03*
X694000Y603000D03*
X711256Y595499D03*
X699899Y602970D03*
X768700Y180900D03*
X787770Y254660D03*
X798770Y259500D03*
X796222Y208966D03*
X784200Y207100D03*
X744482Y202110D03*
X755100Y486700D03*
X739300Y496000D03*
X755100Y481900D03*
X754883Y498500D03*
X810500Y262400D03*
X813491Y206953D03*
X820625Y345848D03*
X801880Y355479D03*
X817800Y479600D03*
X804100Y479200D03*
G54D14*
X65400Y546000D03*
X78231Y562399D03*
X92870Y564415D03*
X97113Y564386D03*
X100619Y564385D03*
X137100Y592000D03*
X133600D03*
X207500Y495580D03*
X252670Y620437D03*
X224346Y621995D03*
X245200Y688300D03*
X365400Y508000D03*
X367600Y701900D03*
X645000Y552900D03*
X721400Y278200D03*
X790360Y239400D03*
G54D23*
X113900Y497300D03*
X165935Y481762D03*
X152316Y570304D03*
X175579Y583387D03*
X179260Y611180D03*
Y607480D03*
X207350Y633450D03*
X266805Y549594D03*
X236400Y633900D03*
X359600Y541400D03*
X369089Y554000D03*
X560800Y64700D03*
X584600Y77400D03*
X665800Y421500D03*
Y417500D03*
Y413500D03*
Y426000D03*
X727268Y294464D03*
X790750Y234770D03*
X757100Y262350D03*
X790900Y224400D03*
X790750Y231350D03*
Y227900D03*
X749600Y262350D03*
X748250Y268900D03*
X734768Y294464D03*
X742268D03*
X756050Y268900D03*
G54D32*
X96287Y572899D03*
X307900Y510700D03*
X356600Y520800D03*
X356480Y586840D03*
X378500Y574700D03*
X647500Y199800D03*
X648698Y296289D03*
X799200Y214550D03*
X795719Y214524D03*
X797099Y239745D03*
X796829Y230525D03*
X792269Y214494D03*
X764900Y210200D03*
X768479Y208664D03*
X759000Y211100D03*
X806210Y214540D03*
X802650Y214530D03*
G54D50*
X466550Y61800D03*
X474050Y65675D03*
Y57925D03*
G54D41*
X193238Y465985D03*
G54D15*
X65400Y549600D03*
X78231Y565999D03*
X92870Y568015D03*
X97113Y567986D03*
X100619Y567985D03*
X137100Y595600D03*
X133600D03*
X207500Y499180D03*
X252670Y624037D03*
X224346Y625595D03*
X245200Y691900D03*
X365400Y511600D03*
X367600Y705500D03*
X645000Y556500D03*
X721400Y281800D03*
X790360Y243000D03*
G54D24*
X110300Y497300D03*
X162335Y481762D03*
X148716Y570304D03*
X171979Y583387D03*
X175660Y611180D03*
Y607480D03*
X203750Y633450D03*
X263205Y549594D03*
X232800Y633900D03*
X356000Y541400D03*
X365489Y554000D03*
X557200Y64700D03*
X581000Y77400D03*
X662200Y421500D03*
Y417500D03*
Y413500D03*
Y426000D03*
X723668Y294464D03*
X731168D03*
X787150Y234770D03*
X753500Y262350D03*
X787300Y224400D03*
X787150Y231350D03*
Y227900D03*
X746000Y262350D03*
X744650Y268900D03*
X738668Y294464D03*
X752450Y268900D03*
G54D33*
X137824Y544746D03*
Y552346D03*
X135449Y558949D03*
Y566549D03*
X122600Y589800D03*
Y597400D03*
X149700Y723000D03*
Y715400D03*
X220300Y525700D03*
Y518100D03*
X247070Y619140D03*
Y626740D03*
X239346Y626876D03*
Y619276D03*
X312272Y192744D03*
Y200344D03*
X327612Y231754D03*
Y239354D03*
X327552Y225184D03*
Y217584D03*
X477943Y34165D03*
Y41765D03*
X679500Y302700D03*
Y310300D03*
X712780Y316840D03*
Y324440D03*
X770090Y226880D03*
Y219280D03*
X760650Y236070D03*
Y228470D03*
X741650Y235600D03*
Y228000D03*
X770300Y270000D03*
Y277600D03*
X801226Y361756D03*
Y369356D03*
X809326Y369256D03*
Y361656D03*
G54D51*
X601500Y367550D03*
X598941D03*
X601500Y359650D03*
X598941D03*
X604059Y367550D03*
Y359650D03*
G54D60*
X736069Y481247D03*
G36*
G01X175989Y669266D02*
G02Y669316I-12800J25D01*
G01X171589D01*
G03Y669266I-8400J-25D01*
G01X175989D01*
G37*
G54D61*
G01X-13131Y-65072D02*
Y-145072D01*
G01D02*
X1244069D01*
G01X-29131Y-65072D02*
Y-33072D01*
G01X-13131Y-65072D02*
X1244069D01*
G01X-13131Y-100572D02*
X1244069D01*
G01X-17131Y-49072D02*
G02I-12000J0D01*
G01X-22281D02*
G02I-6850J0D01*
G01X-13131D02*
X-45131D01*
G01X456569Y-65072D02*
Y-145072D01*
G01X594069Y-65072D02*
Y-145072D01*
G01X709069Y-65072D02*
Y-145072D01*
G01X876569Y-65072D02*
Y-145072D01*
G01X1046569Y-65072D02*
Y-145072D01*
G01X1244069Y-65072D02*
Y-145072D01*
G01X1272069Y-49072D02*
G02I-12000J0D01*
G01X1266919D02*
G02I-6850J0D01*
G01X1276069D02*
X1244069D01*
G01X1260069Y-65072D02*
Y-33072D01*
G54D25*
X140702Y489161D03*
X183100Y503100D03*
X179200Y525000D03*
X170800Y503100D03*
X179000D03*
X155000Y496400D03*
X166700Y503100D03*
X187300Y503000D03*
X166861Y490920D03*
X146300Y496100D03*
X150500Y496380D03*
X191000Y532600D03*
X202700Y532700D03*
X206800Y532580D03*
X205020Y608740D03*
X197191Y633188D03*
X192911Y633248D03*
X215658Y483533D03*
X266816Y561137D03*
X270836Y561119D03*
X246145Y557918D03*
X273490Y584402D03*
X228102Y529442D03*
X210900Y532600D03*
X335962Y702196D03*
X352480Y586164D03*
X365400Y572700D03*
X360300Y558400D03*
X347500Y706300D03*
X345654Y696615D03*
X375500Y704300D03*
X456400Y54400D03*
X512290Y54273D03*
X500411Y51865D03*
X490653Y60737D03*
X629500Y190800D03*
X656665Y298466D03*
X652465Y298566D03*
X732230Y307869D03*
X708300Y449300D03*
X750600Y488900D03*
X828800Y235900D03*
X815726Y363856D03*
G54D52*
X601500Y363600D03*
G54D43*
X214040Y504230D03*
X216600D03*
X219160D03*
Y497730D03*
X214040D03*
G54D16*
X54100Y586350D03*
X46500D03*
X100100Y705700D03*
X92500D03*
X184910Y622020D03*
X192510D03*
X178430Y621990D03*
X170830D03*
X219840Y615320D03*
X227440D03*
X328622Y184294D03*
X321022D03*
X328648Y191994D03*
X321048D03*
X310449Y221407D03*
X318049D03*
X310479Y229157D03*
X318079D03*
X664600Y301300D03*
X622300Y481000D03*
X614700D03*
X622300Y473000D03*
X614700D03*
X731600Y261150D03*
X672200Y301300D03*
X721300Y456900D03*
X728900D03*
X721300Y464700D03*
X728900D03*
X697376Y554429D03*
X704976D03*
X781600Y196000D03*
X774000D03*
X795837Y196018D03*
X788237D03*
X761300Y199300D03*
X753700D03*
X761300Y191500D03*
X753700D03*
X773700Y188200D03*
X781300D03*
X788237Y188218D03*
X795837D03*
X758800Y174900D03*
X766400D03*
X772610Y241950D03*
X780210D03*
X739200Y261150D03*
X810162Y195983D03*
X802562D03*
Y188083D03*
X810162D03*
X830200Y339000D03*
X837800D03*
Y347000D03*
X830200D03*
X835600Y481500D03*
X843200D03*
G54D34*
X105474Y535824D03*
X181148Y568251D03*
X192089Y582625D03*
X185200Y559200D03*
X190680Y615540D03*
X222550Y609150D03*
X384614Y629080D03*
X836800Y332500D03*
G54D62*
G01X13215Y-125739D02*
X14089Y-124864D01*
X14744Y-123406D01*
X15181Y-121363D01*
X14744Y-119614D01*
X13871Y-118447D01*
X12342Y-117572D01*
X6447D01*
Y-135072D01*
X13652D01*
X15181Y-133906D01*
X16054Y-132155D01*
X16491Y-130114D01*
X16054Y-128072D01*
X14744Y-126322D01*
X13215Y-125739D01*
X6447D01*
G01X25912Y-135072D02*
Y-123406D01*
G01Y-125739D02*
X27004Y-124572D01*
X28096Y-123697D01*
X29624Y-123406D01*
X30715Y-123697D01*
X32026Y-124572D01*
G01X41884Y-140322D02*
X43194Y-140905D01*
X44941Y-140322D01*
X46032Y-139156D01*
X46906Y-137697D01*
X48215Y-133031D01*
X51054Y-123406D01*
G01X44067D02*
X48215Y-133031D01*
G01X67462Y-124864D02*
X65934Y-123697D01*
X64624Y-123406D01*
X62877Y-123989D01*
X61567Y-125155D01*
X60694Y-127197D01*
X60475Y-129239D01*
X60694Y-131281D01*
X61567Y-133031D01*
X62877Y-134489D01*
X64624Y-135072D01*
X66152Y-134489D01*
X67462Y-133322D01*
G01X78194Y-127197D02*
X85181D01*
X84526Y-125155D01*
X83434Y-123989D01*
X81906Y-123406D01*
X80377Y-123697D01*
X79067Y-124572D01*
X78194Y-126614D01*
X77757Y-128364D01*
Y-130114D01*
X78194Y-131864D01*
X79286Y-133614D01*
X80596Y-134780D01*
X82124Y-135072D01*
X83652Y-134489D01*
X85181Y-132739D01*
G01X121272Y-119031D02*
X119962Y-118155D01*
X118434Y-117572D01*
X116687D01*
X114722Y-118447D01*
X113194Y-119905D01*
X112102Y-121656D01*
X111229Y-124572D01*
X111010Y-127197D01*
X111447Y-129822D01*
X112102Y-131572D01*
X113412Y-133322D01*
X114941Y-134489D01*
X116469Y-135072D01*
X117997D01*
X119526Y-134489D01*
X120836Y-133614D01*
X121928Y-132448D01*
G01X137899Y-135072D02*
Y-123406D01*
G01Y-125447D02*
X137026Y-124281D01*
X135715Y-123697D01*
X134187Y-123406D01*
X132659Y-123989D01*
X131349Y-125155D01*
X130475Y-126905D01*
X130039Y-129239D01*
X130475Y-131572D01*
X131349Y-133322D01*
X132659Y-134489D01*
X134187Y-135072D01*
X135715Y-134780D01*
X137026Y-133906D01*
X137899Y-132739D01*
G01X147757Y-135072D02*
Y-123406D01*
G01Y-126322D02*
X148631Y-124864D01*
X149941Y-123697D01*
X151687Y-123406D01*
X153215Y-123697D01*
X154526Y-124864D01*
X155181Y-126905D01*
Y-135072D01*
G01X164384Y-140322D02*
X165694Y-140905D01*
X167441Y-140322D01*
X168532Y-139156D01*
X169406Y-137697D01*
X170715Y-133031D01*
X173554Y-123406D01*
G01X166567D02*
X170715Y-133031D01*
G01X186469Y-135072D02*
X185159Y-134780D01*
X183849Y-133614D01*
X182975Y-131572D01*
X182539Y-129239D01*
X182975Y-126905D01*
X183849Y-124864D01*
X185159Y-123697D01*
X186469Y-123406D01*
X187779Y-123697D01*
X189089Y-124864D01*
X189962Y-126905D01*
X190181Y-129239D01*
X189962Y-131572D01*
X189089Y-133614D01*
X187779Y-134780D01*
X186469Y-135072D01*
G01X200257D02*
Y-123406D01*
G01Y-126322D02*
X201131Y-124864D01*
X202441Y-123697D01*
X204187Y-123406D01*
X205715Y-123697D01*
X207026Y-124864D01*
X207681Y-126905D01*
Y-135072D01*
G01X236349Y-117572D02*
X241589D01*
G01X238969D02*
Y-135072D01*
G01X236349D02*
X241589D01*
G01X256469D02*
X254722Y-134780D01*
X253194Y-133614D01*
X251884Y-131864D01*
X251010Y-129822D01*
X250574Y-127489D01*
Y-125155D01*
X251010Y-122822D01*
X251884Y-120780D01*
X253194Y-119031D01*
X254722Y-117864D01*
X256469Y-117572D01*
X258215Y-117864D01*
X259744Y-119031D01*
X261054Y-120780D01*
X261928Y-122822D01*
X262364Y-125155D01*
Y-127489D01*
X261928Y-129822D01*
X261054Y-131864D01*
X259744Y-133614D01*
X258215Y-134780D01*
X256469Y-135072D01*
G01X268292D02*
Y-117572D01*
X273969Y-132155D01*
X279646Y-117572D01*
Y-135072D01*
G01X307877Y-140905D02*
X305694Y-137989D01*
X304602Y-135072D01*
Y-123406D01*
X305694Y-120489D01*
X307877Y-117572D01*
G01X321010Y-123406D02*
X323631Y-135072D01*
X326469Y-123406D01*
X329307Y-135072D01*
X331928Y-123406D01*
G01X340039Y-135655D02*
X347899Y-117572D01*
G01X376349D02*
X381589D01*
G01X378969D02*
Y-135072D01*
G01X376349D02*
X381589D01*
G01X396469D02*
X394722Y-134780D01*
X393194Y-133614D01*
X391884Y-131864D01*
X391010Y-129822D01*
X390574Y-127489D01*
Y-125155D01*
X391010Y-122822D01*
X391884Y-120780D01*
X393194Y-119031D01*
X394722Y-117864D01*
X396469Y-117572D01*
X398215Y-117864D01*
X399744Y-119031D01*
X401054Y-120780D01*
X401928Y-122822D01*
X402364Y-125155D01*
Y-127489D01*
X401928Y-129822D01*
X401054Y-131864D01*
X399744Y-133614D01*
X398215Y-134780D01*
X396469Y-135072D01*
G01X418772Y-119031D02*
X417462Y-118155D01*
X415934Y-117572D01*
X414187D01*
X412222Y-118447D01*
X410694Y-119905D01*
X409602Y-121656D01*
X408729Y-124572D01*
X408510Y-127197D01*
X408947Y-129822D01*
X409602Y-131572D01*
X410912Y-133322D01*
X412441Y-134489D01*
X413969Y-135072D01*
X415497D01*
X417026Y-134489D01*
X418336Y-133614D01*
X419428Y-132448D01*
G01X432561Y-140905D02*
X434744Y-137989D01*
X435836Y-135072D01*
Y-123406D01*
X434744Y-120489D01*
X432561Y-117572D01*
G01X180792Y-90072D02*
Y-72572D01*
X186469Y-87155D01*
X192146Y-72572D01*
Y-90072D01*
G01X203969D02*
X202659Y-89780D01*
X201349Y-88614D01*
X200475Y-86572D01*
X200039Y-84239D01*
X200475Y-81905D01*
X201349Y-79864D01*
X202659Y-78697D01*
X203969Y-78406D01*
X205279Y-78697D01*
X206589Y-79864D01*
X207462Y-81905D01*
X207681Y-84239D01*
X207462Y-86572D01*
X206589Y-88614D01*
X205279Y-89780D01*
X203969Y-90072D01*
G01X225399Y-72572D02*
Y-90072D01*
G01Y-87448D02*
X224526Y-88906D01*
X223215Y-89780D01*
X221687Y-90072D01*
X219941Y-89489D01*
X218631Y-88031D01*
X217757Y-86281D01*
X217539Y-84239D01*
X217757Y-82197D01*
X218631Y-80447D01*
X219941Y-78989D01*
X221687Y-78406D01*
X223215Y-78697D01*
X224307Y-79281D01*
X225399Y-80447D01*
G01X235694Y-82197D02*
X242681D01*
X242026Y-80155D01*
X240934Y-78989D01*
X239406Y-78406D01*
X237877Y-78697D01*
X236567Y-79572D01*
X235694Y-81614D01*
X235257Y-83364D01*
Y-85114D01*
X235694Y-86864D01*
X236786Y-88614D01*
X238096Y-89780D01*
X239624Y-90072D01*
X241152Y-89489D01*
X242681Y-87739D01*
G01X256469Y-90072D02*
Y-72572D01*
G01X490269Y-135072D02*
Y-117572D01*
X487649Y-121072D01*
G01Y-135072D02*
X492889D01*
G01X503621Y-127781D02*
X505149Y-125739D01*
X506459Y-124572D01*
X508206Y-123989D01*
X509734Y-124572D01*
X510826Y-125739D01*
X511699Y-127489D01*
X511917Y-129530D01*
X511699Y-131281D01*
X510826Y-133031D01*
X509515Y-134489D01*
X507987Y-135072D01*
X506241Y-134489D01*
X504712Y-132739D01*
X503839Y-130114D01*
X503621Y-127197D01*
X504057Y-123406D01*
X504712Y-121363D01*
X505804Y-119322D01*
X507332Y-117864D01*
X508861Y-117572D01*
X510389Y-118155D01*
X511481Y-119614D01*
G01X520466Y-131572D02*
X521775Y-133614D01*
X523522Y-134780D01*
X525487Y-135072D01*
X527234Y-134780D01*
X528981Y-133322D01*
X530072Y-131572D01*
X530291Y-129822D01*
X529854Y-127781D01*
X528326Y-126322D01*
X526797Y-125739D01*
X524832D01*
G01X526797D02*
X528107Y-124864D01*
X529199Y-123406D01*
X529636Y-121656D01*
X529199Y-119905D01*
X528107Y-118447D01*
X526142Y-117572D01*
X524177Y-117864D01*
X522212Y-119031D01*
G01X542769Y-135072D02*
Y-117572D01*
X540149Y-121072D01*
G01Y-135072D02*
X545389D01*
G01X560269D02*
X561797Y-134780D01*
X563544Y-133906D01*
X564636Y-132448D01*
X565072Y-130405D01*
X564636Y-128364D01*
X563326Y-126614D01*
X561361Y-125739D01*
X559177D01*
X557867Y-125155D01*
X556775Y-123697D01*
X556339Y-121656D01*
X556994Y-119614D01*
X558522Y-118155D01*
X560269Y-117572D01*
X562015Y-118155D01*
X563544Y-119614D01*
X564199Y-121656D01*
X563762Y-123697D01*
X562671Y-125155D01*
X561361Y-125739D01*
X559177D01*
X557212Y-126614D01*
X555902Y-128364D01*
X555466Y-130405D01*
X555902Y-132448D01*
X556994Y-133906D01*
X558741Y-134780D01*
X560269Y-135072D01*
G01X477152Y-90072D02*
Y-72572D01*
X482392D01*
X484139Y-73447D01*
X485449Y-75489D01*
X485886Y-77822D01*
X485449Y-80155D01*
X484357Y-81905D01*
X482392Y-82781D01*
X477152D01*
G01X503822Y-74031D02*
X502512Y-73155D01*
X500984Y-72572D01*
X499237D01*
X497272Y-73447D01*
X495744Y-74905D01*
X494652Y-76656D01*
X493779Y-79572D01*
X493560Y-82197D01*
X493997Y-84822D01*
X494652Y-86572D01*
X495962Y-88322D01*
X497491Y-89489D01*
X499019Y-90072D01*
X500547D01*
X502076Y-89489D01*
X503386Y-88614D01*
X504478Y-87448D01*
G01X518265Y-80739D02*
X519139Y-79864D01*
X519794Y-78406D01*
X520231Y-76363D01*
X519794Y-74614D01*
X518921Y-73447D01*
X517392Y-72572D01*
X511497D01*
Y-90072D01*
X518702D01*
X520231Y-88906D01*
X521104Y-87155D01*
X521541Y-85114D01*
X521104Y-83072D01*
X519794Y-81322D01*
X518265Y-80739D01*
X511497D01*
G01X527469Y-95905D02*
X540569D01*
G01X546497Y-90072D02*
Y-72572D01*
X556541Y-90072D01*
Y-72572D01*
G01X569019Y-90072D02*
X567272Y-89780D01*
X565744Y-88614D01*
X564434Y-86864D01*
X563560Y-84822D01*
X563124Y-82489D01*
Y-80155D01*
X563560Y-77822D01*
X564434Y-75780D01*
X565744Y-74031D01*
X567272Y-72864D01*
X569019Y-72572D01*
X570765Y-72864D01*
X572294Y-74031D01*
X573604Y-75780D01*
X574478Y-77822D01*
X574914Y-80155D01*
Y-82489D01*
X574478Y-84822D01*
X573604Y-86864D01*
X572294Y-88614D01*
X570765Y-89780D01*
X569019Y-90072D01*
G01X647421Y-120489D02*
X648731Y-118739D01*
X650259Y-117864D01*
X652006Y-117572D01*
X654189Y-118155D01*
X655717Y-119614D01*
X656154Y-121363D01*
X655936Y-123114D01*
X655062Y-124572D01*
X650696Y-127489D01*
X648731Y-129530D01*
X647421Y-132448D01*
X646984Y-135072D01*
X656154D01*
G01X619860Y-72572D02*
X625319Y-90072D01*
X630778Y-72572D01*
G01X647186Y-90072D02*
X638452D01*
Y-72572D01*
X647186D01*
G01X643692Y-81030D02*
X638452D01*
G01X655952Y-90072D02*
Y-72572D01*
X661411D01*
X663157Y-73447D01*
X664249Y-74614D01*
X664686Y-76947D01*
X664249Y-79281D01*
X662939Y-80739D01*
X661411Y-81614D01*
X655952D01*
G01X661411D02*
X664686Y-90072D01*
G01X677819Y-90655D02*
X677382Y-90364D01*
Y-89780D01*
X677819Y-89489D01*
X678256Y-89780D01*
Y-90364D01*
X677819Y-90655D01*
G01X817273Y-125739D02*
X816399Y-124864D01*
X815744Y-123406D01*
X815307Y-121363D01*
X815744Y-119614D01*
X816617Y-118447D01*
X818146Y-117572D01*
X824041D01*
Y-135072D01*
X816836D01*
X815307Y-133906D01*
X814434Y-132155D01*
X813997Y-130114D01*
X814434Y-128072D01*
X815744Y-126322D01*
X817273Y-125739D01*
X824041D01*
G01X806104Y-132739D02*
X804357Y-134197D01*
X802392Y-135072D01*
X800646D01*
X798899Y-134197D01*
X797589Y-132739D01*
X796934Y-130697D01*
X797371Y-128656D01*
X798462Y-126905D01*
X800427Y-125739D01*
X803047Y-125155D01*
X804576Y-123989D01*
X805231Y-121947D01*
X804794Y-119905D01*
X803702Y-118447D01*
X802174Y-117572D01*
X800646D01*
X799117Y-118155D01*
X797807Y-119614D01*
G01X789696Y-135072D02*
Y-117572D01*
X784019Y-132155D01*
X778342Y-117572D01*
Y-135072D01*
G01X771322D02*
Y-117572D01*
X766956D01*
X765209Y-118447D01*
X763899Y-119614D01*
X762807Y-121363D01*
X761934Y-123406D01*
X761716Y-126322D01*
X761934Y-129239D01*
X762807Y-131281D01*
X763899Y-133031D01*
X765209Y-134197D01*
X766956Y-135072D01*
X771322D01*
G01X753402Y-72572D02*
Y-90072D01*
X762136D01*
G01X779199D02*
Y-78406D01*
G01Y-80447D02*
X778326Y-79281D01*
X777015Y-78697D01*
X775487Y-78406D01*
X773959Y-78989D01*
X772649Y-80155D01*
X771775Y-81905D01*
X771339Y-84239D01*
X771775Y-86572D01*
X772649Y-88322D01*
X773959Y-89489D01*
X775487Y-90072D01*
X777015Y-89780D01*
X778326Y-88906D01*
X779199Y-87739D01*
G01X788184Y-95322D02*
X789494Y-95905D01*
X791241Y-95322D01*
X792332Y-94156D01*
X793206Y-92697D01*
X794515Y-88031D01*
X797354Y-78406D01*
G01X790367D02*
X794515Y-88031D01*
G01X806994Y-82197D02*
X813981D01*
X813326Y-80155D01*
X812234Y-78989D01*
X810706Y-78406D01*
X809177Y-78697D01*
X807867Y-79572D01*
X806994Y-81614D01*
X806557Y-83364D01*
Y-85114D01*
X806994Y-86864D01*
X808086Y-88614D01*
X809396Y-89780D01*
X810924Y-90072D01*
X812452Y-89489D01*
X813981Y-87739D01*
G01X824712Y-90072D02*
Y-78406D01*
G01Y-80739D02*
X825804Y-79572D01*
X826896Y-78697D01*
X828424Y-78406D01*
X829515Y-78697D01*
X830826Y-79572D01*
G01X917819Y-135072D02*
X916072Y-134780D01*
X914544Y-133614D01*
X913234Y-131864D01*
X912360Y-129822D01*
X911924Y-127489D01*
Y-125155D01*
X912360Y-122822D01*
X913234Y-120780D01*
X914544Y-119031D01*
X916072Y-117864D01*
X917819Y-117572D01*
X919565Y-117864D01*
X921094Y-119031D01*
X922404Y-120780D01*
X923278Y-122822D01*
X923714Y-125155D01*
Y-127489D01*
X923278Y-129822D01*
X922404Y-131864D01*
X921094Y-133614D01*
X919565Y-134780D01*
X917819Y-135072D01*
G01X919565Y-130405D02*
X922186Y-135072D01*
G01X930516Y-117572D02*
Y-130114D01*
X931389Y-132739D01*
X933136Y-134489D01*
X935319Y-135072D01*
X937502Y-134489D01*
X939249Y-132739D01*
X940122Y-130114D01*
Y-117572D01*
G01X950199D02*
X955439D01*
G01X952819D02*
Y-135072D01*
G01X950199D02*
X955439D01*
G01X965297D02*
Y-117572D01*
X975341Y-135072D01*
Y-117572D01*
G01X992622Y-119031D02*
X991312Y-118155D01*
X989784Y-117572D01*
X988037D01*
X986072Y-118447D01*
X984544Y-119905D01*
X983452Y-121656D01*
X982579Y-124572D01*
X982360Y-127197D01*
X982797Y-129822D01*
X983452Y-131572D01*
X984762Y-133322D01*
X986291Y-134489D01*
X987819Y-135072D01*
X989347D01*
X990876Y-134489D01*
X992186Y-133614D01*
X993278Y-132448D01*
G01X1005319Y-135072D02*
Y-127197D01*
X1000952Y-117572D01*
G01X1009686D02*
X1005319Y-127197D01*
G01X895516Y-90072D02*
Y-72572D01*
X899882D01*
X901629Y-73447D01*
X902939Y-74614D01*
X904031Y-76363D01*
X904904Y-78406D01*
X905122Y-81322D01*
X904904Y-84239D01*
X904031Y-86281D01*
X902939Y-88031D01*
X901629Y-89197D01*
X899882Y-90072D01*
X895516D01*
G01X914544Y-82197D02*
X921531D01*
X920876Y-80155D01*
X919784Y-78989D01*
X918256Y-78406D01*
X916727Y-78697D01*
X915417Y-79572D01*
X914544Y-81614D01*
X914107Y-83364D01*
Y-85114D01*
X914544Y-86864D01*
X915636Y-88614D01*
X916946Y-89780D01*
X918474Y-90072D01*
X920002Y-89489D01*
X921531Y-87739D01*
G01X932044Y-88031D02*
X933136Y-89197D01*
X934664Y-90072D01*
X935974D01*
X937284Y-89489D01*
X938157Y-88614D01*
X938594Y-87448D01*
X938376Y-85697D01*
X937502Y-84822D01*
X933572Y-83072D01*
X932699Y-81030D01*
X933136Y-79572D01*
X934009Y-78697D01*
X935319Y-78406D01*
X936629Y-78697D01*
X937939Y-79572D01*
G01X952819Y-78406D02*
Y-90072D01*
G01Y-73739D02*
X952382Y-73447D01*
Y-72864D01*
X952819Y-72572D01*
X953256Y-72864D01*
Y-73447D01*
X952819Y-73739D01*
G01X967262Y-94447D02*
X968791Y-95614D01*
X970537Y-95905D01*
X972065Y-95614D01*
X973376Y-94156D01*
X974249Y-92114D01*
Y-78406D01*
G01Y-80739D02*
X973376Y-79572D01*
X972065Y-78697D01*
X970537Y-78406D01*
X968791Y-78989D01*
X967699Y-80155D01*
X966825Y-82197D01*
X966389Y-84239D01*
X966607Y-85989D01*
X967481Y-88031D01*
X968791Y-89489D01*
X970537Y-90072D01*
X971847Y-89780D01*
X973376Y-88614D01*
X974249Y-87448D01*
G01X984107Y-90072D02*
Y-78406D01*
G01Y-81322D02*
X984981Y-79864D01*
X986291Y-78697D01*
X988037Y-78406D01*
X989565Y-78697D01*
X990876Y-79864D01*
X991531Y-81905D01*
Y-90072D01*
G01X1002044Y-82197D02*
X1009031D01*
X1008376Y-80155D01*
X1007284Y-78989D01*
X1005756Y-78406D01*
X1004227Y-78697D01*
X1002917Y-79572D01*
X1002044Y-81614D01*
X1001607Y-83364D01*
Y-85114D01*
X1002044Y-86864D01*
X1003136Y-88614D01*
X1004446Y-89780D01*
X1005974Y-90072D01*
X1007502Y-89489D01*
X1009031Y-87739D01*
G01X1019762Y-90072D02*
Y-78406D01*
G01Y-80739D02*
X1020854Y-79572D01*
X1021946Y-78697D01*
X1023474Y-78406D01*
X1024565Y-78697D01*
X1025876Y-79572D01*
G01X1066519Y-117572D02*
X1064772Y-118155D01*
X1063462Y-119614D01*
X1062589Y-121363D01*
X1061934Y-123697D01*
X1061716Y-126322D01*
X1061934Y-128947D01*
X1062589Y-131281D01*
X1063462Y-133031D01*
X1064772Y-134489D01*
X1066519Y-135072D01*
X1068265Y-134489D01*
X1069576Y-133031D01*
X1070449Y-131281D01*
X1071104Y-128947D01*
X1071322Y-126322D01*
X1071104Y-123697D01*
X1070449Y-121363D01*
X1069576Y-119614D01*
X1068265Y-118155D01*
X1066519Y-117572D01*
G01X1084019Y-135072D02*
X1085547Y-134780D01*
X1087294Y-133906D01*
X1088386Y-132448D01*
X1088822Y-130405D01*
X1088386Y-128364D01*
X1087076Y-126614D01*
X1085111Y-125739D01*
X1082927D01*
X1081617Y-125155D01*
X1080525Y-123697D01*
X1080089Y-121656D01*
X1080744Y-119614D01*
X1082272Y-118155D01*
X1084019Y-117572D01*
X1085765Y-118155D01*
X1087294Y-119614D01*
X1087949Y-121656D01*
X1087512Y-123697D01*
X1086421Y-125155D01*
X1085111Y-125739D01*
X1082927D01*
X1080962Y-126614D01*
X1079652Y-128364D01*
X1079216Y-130405D01*
X1079652Y-132448D01*
X1080744Y-133906D01*
X1082491Y-134780D01*
X1084019Y-135072D01*
G01X1097589Y-135655D02*
X1105449Y-117572D01*
G01X1119019D02*
X1117272Y-118155D01*
X1115962Y-119614D01*
X1115089Y-121363D01*
X1114434Y-123697D01*
X1114216Y-126322D01*
X1114434Y-128947D01*
X1115089Y-131281D01*
X1115962Y-133031D01*
X1117272Y-134489D01*
X1119019Y-135072D01*
X1120765Y-134489D01*
X1122076Y-133031D01*
X1122949Y-131281D01*
X1123604Y-128947D01*
X1123822Y-126322D01*
X1123604Y-123697D01*
X1122949Y-121363D01*
X1122076Y-119614D01*
X1120765Y-118155D01*
X1119019Y-117572D01*
G01X1136082Y-135072D02*
X1136519Y-131281D01*
X1137174Y-128072D01*
X1138047Y-125155D01*
X1139139Y-121947D01*
X1140886Y-117572D01*
X1132152D01*
G01X1150089Y-135655D02*
X1157949Y-117572D01*
G01X1167371Y-120489D02*
X1168681Y-118739D01*
X1170209Y-117864D01*
X1171956Y-117572D01*
X1174139Y-118155D01*
X1175667Y-119614D01*
X1176104Y-121363D01*
X1175886Y-123114D01*
X1175012Y-124572D01*
X1170646Y-127489D01*
X1168681Y-129530D01*
X1167371Y-132448D01*
X1166934Y-135072D01*
X1176104D01*
G01X1189019Y-117572D02*
X1187272Y-118155D01*
X1185962Y-119614D01*
X1185089Y-121363D01*
X1184434Y-123697D01*
X1184216Y-126322D01*
X1184434Y-128947D01*
X1185089Y-131281D01*
X1185962Y-133031D01*
X1187272Y-134489D01*
X1189019Y-135072D01*
X1190765Y-134489D01*
X1192076Y-133031D01*
X1192949Y-131281D01*
X1193604Y-128947D01*
X1193822Y-126322D01*
X1193604Y-123697D01*
X1192949Y-121363D01*
X1192076Y-119614D01*
X1190765Y-118155D01*
X1189019Y-117572D01*
G01X1206519Y-135072D02*
Y-117572D01*
X1203899Y-121072D01*
G01Y-135072D02*
X1209139D01*
G01X1223582D02*
X1224019Y-131281D01*
X1224674Y-128072D01*
X1225547Y-125155D01*
X1226639Y-121947D01*
X1228386Y-117572D01*
X1219652D01*
G01X1114216Y-90072D02*
Y-72572D01*
X1118582D01*
X1120329Y-73447D01*
X1121639Y-74614D01*
X1122731Y-76363D01*
X1123604Y-78406D01*
X1123822Y-81322D01*
X1123604Y-84239D01*
X1122731Y-86281D01*
X1121639Y-88031D01*
X1120329Y-89197D01*
X1118582Y-90072D01*
X1114216D01*
G01X1140449D02*
Y-78406D01*
G01Y-80447D02*
X1139576Y-79281D01*
X1138265Y-78697D01*
X1136737Y-78406D01*
X1135209Y-78989D01*
X1133899Y-80155D01*
X1133025Y-81905D01*
X1132589Y-84239D01*
X1133025Y-86572D01*
X1133899Y-88322D01*
X1135209Y-89489D01*
X1136737Y-90072D01*
X1138265Y-89780D01*
X1139576Y-88906D01*
X1140449Y-87739D01*
G01X1154019Y-72572D02*
Y-90072D01*
G01X1150962Y-78406D02*
X1157076D01*
G01X1168244Y-82197D02*
X1175231D01*
X1174576Y-80155D01*
X1173484Y-78989D01*
X1171956Y-78406D01*
X1170427Y-78697D01*
X1169117Y-79572D01*
X1168244Y-81614D01*
X1167807Y-83364D01*
Y-85114D01*
X1168244Y-86864D01*
X1169336Y-88614D01*
X1170646Y-89780D01*
X1172174Y-90072D01*
X1173702Y-89489D01*
X1175231Y-87739D01*
G01X3937Y0D02*
X116260D01*
G01X0Y3937D02*
G03X3937Y0I3937J0D01*
G01X0Y723480D02*
Y3937D01*
G01X416Y725241D02*
G03X0Y723480I3521J-1761D01*
G01X18597Y761603D02*
X416Y725241D01*
G01X77756Y98425D02*
G03X63976I-6890J0D01*
G01D02*
G03X77756I6890J0D01*
G01X83071Y245079D02*
G03Y231693I0J-6693D01*
G01X77756Y472441D02*
G03X63976I-6890J0D01*
G01D02*
G03X77756I6890J0D01*
G01X57087Y740157D02*
G03X41339I-7874J0D01*
G01D02*
G03X57087I7874J0D01*
G01X22118Y763780D02*
G03X18597Y761603I1J-3937D01*
G01X386149Y763780D02*
X22118D01*
G01X128071Y3937D02*
G03X132008Y0I3937J0D01*
G01X116260D02*
G03X120197Y3937I0J3937D01*
G01X132008Y0D02*
X275709D01*
G01X120197Y3937D02*
Y429331D01*
G01X128071Y59055D02*
Y3937D01*
G01Y59055D02*
G03X120197I-3937J0D01*
G01X128071D02*
G03X120197I-3937J0D01*
G01X128071Y98425D02*
Y421457D01*
G01X120197Y98425D02*
G03X128071I3937J0D01*
G01X120197D02*
G03X128071I3937J0D01*
G01X96457Y231693D02*
G03Y245079I0J6693D01*
G01X83071D02*
X96457D01*
G01Y231693D02*
X83071D01*
G01X96654Y413583D02*
G03X83661I-6496J0D01*
G01D02*
G03X96654I6496J0D01*
G01X132008Y425394D02*
G03X128071Y421457I0J-3937D01*
G01X124134Y433268D02*
X283583D01*
G01X124134D02*
G03X120197Y429331I0J-3937D01*
G01X184173Y425394D02*
X132008D01*
G01X213480Y37075D02*
G03I-4291J0D01*
G01Y383483D02*
G03I-4291J0D01*
G01X184173Y425394D02*
G03Y433268I0J3937D01*
G01Y425394D02*
G03Y433268I0J3937D01*
G01X171457Y669291D02*
G03X154921I-8268J0D01*
G01D02*
G03X171457I8268J0D01*
G01X223543Y425394D02*
X275709D01*
G01X223543Y433268D02*
G03Y425394I0J-3937D01*
G01Y433268D02*
G03Y425394I0J-3937D01*
G01X275709Y0D02*
G03X279646Y3937I0J3937D01*
G01X291457Y0D02*
X921260D01*
G01X287520Y3937D02*
G03X291457Y0I3937J0D01*
G01X287520Y429331D02*
Y3937D01*
G01X279646Y59055D02*
Y3937D01*
G01X287520Y59055D02*
G03X279646I-3937J0D01*
G01X287520D02*
G03X279646I-3937J0D01*
G01Y98425D02*
Y421457D01*
G01Y98425D02*
G03X287520I3937J0D01*
G01X279646D02*
G03X287520I3937J0D01*
G01X315551Y157677D02*
G03X302559I-6496J0D01*
G01D02*
G03X315551I6496J0D01*
G01X315945Y406890D02*
G03Y420276I0J6693D01*
G01X302559D02*
X315945D01*
G01X302559D02*
G03Y406890I0J-6693D01*
G01X315945D02*
X302559D01*
G01X279646Y421457D02*
G03X275709Y425394I-3937J0D01*
G01X287520Y429331D02*
G03X283583Y433268I-3937J0D01*
G01X321850Y472441D02*
G03X308071I-6889J0D01*
G01D02*
G03X321850I6889J0D01*
G01X412402Y39370D02*
G03X398622I-6890J0D01*
G01D02*
G03X412402I6890J0D01*
G01X371063Y740157D02*
G03X357283I-6890J0D01*
G01D02*
G03X371063I6890J0D01*
G01X403756Y763780D02*
G03X400235Y758082I0J-3937D01*
G01X389671Y761603D02*
G03X386149Y763780I-3522J-1760D01*
G01X414895Y728762D02*
X400235Y758082D01*
G01X407852Y725241D02*
X389671Y761603D01*
G01X403756Y763780D02*
X428096D01*
G01X416142Y200787D02*
G03X420079Y196850I3937J0D01*
G01X408268Y188976D02*
Y723480D01*
G01Y188976D02*
G03X412205I1968J0D01*
G01X556299Y196850D02*
X420079D01*
G01X564173Y188976D02*
X412205D01*
G01X416142Y316929D02*
Y200787D01*
G01Y316929D02*
G03X408268I-3937J0D01*
G01X416142D02*
G03X408268I-3937J0D01*
G01X416142Y347638D02*
Y690803D01*
G01X408268Y347638D02*
G03X416142I3937J0D01*
G01X408268D02*
G03X416142I3937J0D01*
G01Y721512D02*
Y723481D01*
G01Y723482D02*
G03X414894Y728764I-11811J-2D01*
G01X408268Y723480D02*
G03X407852Y725241I-3937J0D01*
G01X408268Y721512D02*
G03X416142I3937J0D01*
G01Y690803D02*
G03X408268I-3937J0D01*
G01Y721512D02*
G03X416142I3937J0D01*
G01Y690803D02*
G03X408268I-3937J0D01*
G01X428096Y763780D02*
G03X435970I3937J0D01*
G01D02*
X572622D01*
G01X483800Y137224D02*
G03X493878I5039J0D01*
G01X493563Y164744D02*
G03X484115I-4724J0D01*
G01D02*
G03X493563I4724J0D01*
G01X493878Y137224D02*
G03X483800I-5039J0D01*
G01X493622Y245605D02*
G03I-4291J0D01*
G01Y698924D02*
G03I-4291J0D01*
G01X556299Y196850D02*
G03X560236Y200787I0J3937D01*
G01X564173Y188976D02*
G03X568110I1968J0D01*
G01Y723480D02*
Y188976D01*
G01X560236Y316929D02*
Y200787D01*
G01X568110Y316929D02*
G03X560236I-3937J0D01*
G01X568110D02*
G03X560236I-3937J0D01*
G01Y690803D02*
Y347638D01*
G01D02*
G03X568110I3937J0D01*
G01X560236D02*
G03X568110I3937J0D01*
G01X560236Y721512D02*
Y723481D01*
G01X561484Y728764D02*
G03X560236Y723482I10563J-5284D01*
G01X568526Y725241D02*
G03X568110Y723480I3521J-1761D01*
G01X560236Y721512D02*
G03X568110I3937J0D01*
G01Y690803D02*
G03X560236I-3937J0D01*
G01Y721512D02*
G03X568110I3937J0D01*
G01Y690803D02*
G03X560236I-3937J0D01*
G01X576143Y758082D02*
G03X572622Y763780I-3521J1761D01*
G01X576143Y758082D02*
X561483Y728762D01*
G01X586707Y761603D02*
X568526Y725241D01*
G01X590228Y763780D02*
G03X586707Y761603I1J-3937D01*
G01X903079Y763780D02*
X590228D01*
G01X634252Y57874D02*
G03X625591I-4331J0D01*
G01D02*
G03X634252I4331J0D01*
G01X658661Y180000D02*
G03X646850I-5905J0D01*
G01D02*
G03X658661I5906J0D01*
G01X619094Y433071D02*
G03X605315I-6889J0D01*
G01D02*
G03X619094I6890J0D01*
G01Y740157D02*
G03X605315I-6889J0D01*
G01D02*
G03X619094I6890J0D01*
G01X712992Y57874D02*
G03X704331I-4331J0D01*
G01D02*
G03X712992I4330J0D01*
G01X859449Y332598D02*
G03X871260I5905J0D01*
G01D02*
G03X859449I-5906J0D01*
G01X921260Y0D02*
G03X925197Y3937I0J3937D01*
G01X883858Y59055D02*
G03X868110I-7874J0D01*
G01D02*
G03X883858I7874J0D01*
G01X925197Y3937D02*
Y723480D01*
G01X882874Y433071D02*
G03X869094I-6890J0D01*
G01D02*
G03X882874I6890J0D01*
G01X925197Y723480D02*
G03X924781Y725241I-3937J0D01*
G01X882874Y740157D02*
G03X869094I-6890J0D01*
G01D02*
G03X882874I6890J0D01*
G01X906600Y761603D02*
G03X903079Y763780I-3522J-1760D01*
G01X924781Y725241D02*
X906600Y761603D01*
G54D44*
X336282Y386493D03*
X332407Y393993D03*
X340157D03*
G54D35*
X99874Y535824D03*
X175548Y568251D03*
X186489Y582625D03*
X179600Y559200D03*
X185080Y615540D03*
X216950Y609150D03*
X379014Y629080D03*
X831200Y332500D03*
G54D17*
X78524Y558398D03*
X78525Y554363D03*
X117930Y499550D03*
X98076Y560166D03*
X98044Y555240D03*
X149700Y460200D03*
X158530Y510140D03*
X173900Y517000D03*
X149565Y481057D03*
X149685Y468562D03*
X153988Y522134D03*
X153958Y517677D03*
X172402Y574058D03*
X148354Y588802D03*
X197490Y611700D03*
X169493Y635303D03*
X196760Y599340D03*
X184250Y607360D03*
X203790Y637250D03*
X197916Y620590D03*
X148057Y602562D03*
X224409Y558053D03*
X265912Y583809D03*
X224300Y585900D03*
X224375Y576816D03*
X224000Y571900D03*
X223200Y593200D03*
X243400Y531240D03*
X242200Y543100D03*
X245800Y606260D03*
X238150Y610860D03*
X211700Y642200D03*
X246365Y594250D03*
X235362Y606422D03*
X223200Y597200D03*
X232800Y637900D03*
X235410Y602160D03*
X232800Y642300D03*
X222092Y642006D03*
X317300Y552900D03*
X312700Y573000D03*
X308950Y658050D03*
X316500Y658100D03*
X338200Y696100D03*
X344117Y575841D03*
X356096Y545220D03*
X363600Y540600D03*
X375716Y620503D03*
X362500Y664200D03*
X375757Y695203D03*
X489779Y30448D03*
X507300Y65000D03*
X489800Y38500D03*
X479900Y58900D03*
Y62900D03*
X613286Y367271D03*
X707652Y261999D03*
X745700Y208500D03*
X821300Y240200D03*
X820100Y248200D03*
X821268Y235964D03*
X821300Y244200D03*
X811000Y257800D03*
X814500Y310400D03*
X832300Y353000D03*
G54D53*
X658585Y152347D03*
Y150147D03*
X656085Y152347D03*
Y150147D03*
X663784Y152447D03*
Y150247D03*
X661284Y152447D03*
Y150247D03*
X666685Y152447D03*
Y150247D03*
X653384Y152347D03*
Y150147D03*
X650884Y152347D03*
Y150147D03*
X669185Y152447D03*
Y150247D03*
X786880Y262090D03*
Y259890D03*
X781580Y261940D03*
Y259740D03*
X790800Y297700D03*
Y295500D03*
X770800Y302100D03*
Y299900D03*
X757000Y277950D03*
Y275750D03*
X752000Y288200D03*
Y286000D03*
X754800Y277950D03*
Y275750D03*
X775200Y280800D03*
Y278600D03*
X803100Y292800D03*
Y290600D03*
G54D26*
X140702Y492561D03*
X183100Y506500D03*
X170800D03*
X179000D03*
X155000Y499800D03*
X166700Y506500D03*
X187300Y506400D03*
X166861Y494320D03*
X146300Y499500D03*
X150500Y499780D03*
X179200Y528400D03*
X191000Y536000D03*
X202700Y536100D03*
X206800Y535980D03*
X205020Y612140D03*
X197191Y636588D03*
X192911Y636648D03*
X215658Y486933D03*
X266816Y564537D03*
X270836Y564519D03*
X246145Y561318D03*
X273490Y587802D03*
X228102Y532842D03*
X210900Y536000D03*
X335962Y705596D03*
X352480Y589564D03*
X365400Y576100D03*
X360300Y561800D03*
X347500Y709700D03*
X345654Y700015D03*
X375500Y707700D03*
X456400Y57800D03*
X512290Y57673D03*
X500411Y55265D03*
X490653Y64137D03*
X629500Y194200D03*
X656665Y301866D03*
X652465Y301966D03*
X732230Y311269D03*
X708300Y452700D03*
X750600Y492300D03*
X828800Y239300D03*
X815726Y367256D03*
G54D18*
X64350Y582500D03*
X129100Y597100D03*
X141189Y596337D03*
X209445Y525049D03*
X148840Y555135D03*
X153495Y555166D03*
X228384Y627209D03*
X375600Y604200D03*
X349200Y637700D03*
X354000D03*
X685700Y309600D03*
X690620Y323740D03*
X697200Y547900D03*
X706506Y603099D03*
X794726Y368356D03*
X759900Y492400D03*
G54D45*
X380500Y24500D03*
X369500D03*
X467500Y25500D03*
X478500D03*
X744100Y474900D03*
X755100D03*
G54D54*
X622025Y211250D03*
X623995D03*
X625960D03*
X627930D03*
X629900D03*
X631870D03*
X633835D03*
X635805D03*
X637775D03*
X639740D03*
X641710D03*
X643680D03*
X645645D03*
X647615D03*
X649585D03*
X651555D03*
X653520D03*
X655490D03*
X657460D03*
X659425D03*
X661395D03*
X663365D03*
X665330D03*
X667300D03*
Y286950D03*
X665330D03*
X663365D03*
X661395D03*
X659425D03*
X657460D03*
X655490D03*
X653520D03*
X651555D03*
X649585D03*
X647615D03*
X645645D03*
X643680D03*
X641710D03*
X639740D03*
X637775D03*
X635805D03*
X633835D03*
X631870D03*
X629900D03*
X627930D03*
X625960D03*
X623995D03*
X622025D03*
X669270Y211250D03*
X671240D03*
X673205D03*
X675175D03*
Y286950D03*
X673205D03*
X671240D03*
X669270D03*
G54D27*
X121330Y499550D03*
X81924Y558398D03*
X81925Y554363D03*
X101476Y560166D03*
X101444Y555240D03*
X153100Y460200D03*
X161930Y510140D03*
X177300Y517000D03*
X152965Y481057D03*
X153085Y468562D03*
X157388Y522134D03*
X157358Y517677D03*
X175802Y574058D03*
X151754Y588802D03*
X200890Y611700D03*
X172893Y635303D03*
X200160Y599340D03*
X187650Y607360D03*
X207190Y637250D03*
X201316Y620590D03*
X151457Y602562D03*
X227809Y558053D03*
X269312Y583809D03*
X227700Y585900D03*
X227775Y576816D03*
X227400Y571900D03*
X226600Y593200D03*
X246800Y531240D03*
X245600Y543100D03*
X249200Y606260D03*
X241550Y610860D03*
X215100Y642200D03*
X249765Y594250D03*
X238762Y606422D03*
X226600Y597200D03*
X236200Y637900D03*
X238810Y602160D03*
X236200Y642300D03*
X225492Y642006D03*
X320700Y552900D03*
X316100Y573000D03*
X312350Y658050D03*
X319900Y658100D03*
X347517Y575841D03*
X359496Y545220D03*
X367000Y540600D03*
X379116Y620503D03*
X365900Y664200D03*
X341600Y696100D03*
X379157Y695203D03*
X493179Y30448D03*
X510700Y65000D03*
X493200Y38500D03*
X483300Y58900D03*
Y62900D03*
X616686Y367271D03*
X711052Y261999D03*
X749100Y208500D03*
X824700Y240200D03*
X823500Y248200D03*
X824668Y235964D03*
X824700Y244200D03*
X814400Y257800D03*
X817900Y310400D03*
X835700Y353000D03*
G54D36*
X141887Y560491D03*
X144037Y549486D03*
X204700Y519400D03*
X195400Y519500D03*
X200055Y519351D03*
X146567Y560391D03*
X151257Y560423D03*
X181505Y575791D03*
X160964Y717468D03*
X214100Y519500D03*
X445900Y31900D03*
X507895Y54797D03*
X496000Y50615D03*
X706580Y316040D03*
G54D46*
X373850Y563338D03*
X366350Y559463D03*
Y567213D03*
G54D28*
X126850Y490210D03*
Y487650D03*
Y485090D03*
X120350D03*
Y490210D03*
X320650Y514560D03*
Y512000D03*
Y509440D03*
X314150D03*
Y514560D03*
X369350Y522460D03*
Y519900D03*
Y517340D03*
X362850D03*
Y522460D03*
X364930Y534960D03*
Y532400D03*
Y529840D03*
X358430D03*
Y534960D03*
X382370Y706140D03*
Y708700D03*
Y711260D03*
X388870D03*
Y706140D03*
X354570Y702040D03*
Y704600D03*
Y707160D03*
X361070D03*
Y702040D03*
X354470Y689440D03*
Y692000D03*
Y694560D03*
X360970D03*
Y689440D03*
X573750Y64940D03*
Y67500D03*
X580250Y64940D03*
X573750Y70060D03*
X580250D03*
X551250Y69940D03*
Y72500D03*
Y75060D03*
X557750D03*
Y69940D03*
G54D55*
X689500Y305900D03*
Y308100D03*
X692000Y305900D03*
Y308100D03*
X774350Y255250D03*
Y257450D03*
X791617Y318400D03*
Y320600D03*
X793817Y318400D03*
Y320600D03*
X788817Y318400D03*
Y320600D03*
X740117Y318400D03*
Y320600D03*
X742317Y318400D03*
Y320600D03*
X746617Y318400D03*
Y320600D03*
X748817Y318400D03*
Y320600D03*
X754617Y318400D03*
Y320600D03*
X756817Y318400D03*
Y320600D03*
X759617Y318400D03*
Y320600D03*
X761817Y318400D03*
Y320600D03*
X776617Y318400D03*
Y320600D03*
X778817Y318400D03*
Y320600D03*
X781617Y318400D03*
Y320600D03*
X783817Y318400D03*
Y320600D03*
X786617Y318400D03*
Y320600D03*
X777700Y307300D03*
Y309500D03*
G54D37*
X141887Y566091D03*
X144037Y555086D03*
X204700Y525000D03*
X195400Y525100D03*
X200055Y524951D03*
X146567Y565991D03*
X151257Y566023D03*
X181505Y581391D03*
X160964Y723068D03*
X214100Y525100D03*
X445900Y37500D03*
X507895Y60397D03*
X496000Y56215D03*
X706580Y321640D03*
G54D19*
X64350Y576900D03*
X129100Y591500D03*
X141189Y590737D03*
X209445Y519449D03*
X148840Y549535D03*
X153495Y549566D03*
X228384Y621609D03*
X375600Y598600D03*
X349200Y632100D03*
X354000D03*
X685700Y304000D03*
X690620Y318140D03*
X697200Y542300D03*
X706506Y597499D03*
X794726Y362756D03*
X759900Y486800D03*
G54D47*
X361800Y603500D03*
Y599900D03*
X367620Y603164D03*
Y599564D03*
G54D56*
X699925Y313194D03*
Y324194D03*
X786600Y452500D03*
Y441500D03*
X777600Y452500D03*
Y441500D03*
G54D29*
X100130Y576452D03*
X171969Y579940D03*
X201170Y552500D03*
X184120Y611240D03*
X222019Y634188D03*
X215720Y605070D03*
X211700Y638400D03*
X211100Y649500D03*
X321700Y681900D03*
X387800Y700700D03*
X368200Y689500D03*
X609700Y358900D03*
X722850Y256550D03*
X722550Y231460D03*
X722760Y225060D03*
X722700Y262300D03*
X730370Y227400D03*
X730360Y230840D03*
X723140Y249850D03*
X723370Y243700D03*
X722829Y237714D03*
X727350Y284210D03*
X723063Y268702D03*
X732520Y288150D03*
X725100Y275200D03*
X743050Y249900D03*
X771500Y233900D03*
X762300Y262250D03*
X777400Y214700D03*
X738300Y218800D03*
X745800D03*
X777400Y218100D03*
X784919Y218074D03*
X760900Y269000D03*
X746168Y294464D03*
X740060Y287810D03*
X800800Y246800D03*
G54D38*
X83000Y734600D03*
X838300Y36700D03*
X888800Y696900D03*
G54D48*
X367113Y622707D03*
Y626307D03*
X718590Y319060D03*
Y322660D03*
X726350Y319080D03*
Y322680D03*
X722390Y319060D03*
Y322660D03*
G54D39*
X159400Y498300D03*
X165030Y539170D03*
X156391Y590972D03*
X197400Y549000D03*
X153624Y543694D03*
X161750Y535000D03*
X170545Y539779D03*
X175200Y555000D03*
X202380Y567970D03*
X207820Y570860D03*
X206900Y577100D03*
X190500Y547100D03*
X178100Y548700D03*
X155660Y599140D03*
X170200Y603600D03*
X155343Y609168D03*
X158862Y614107D03*
X177750Y603250D03*
X239200Y527000D03*
X220832Y551776D03*
X231892Y546871D03*
X221956Y544587D03*
X223192Y567000D03*
X219688Y587796D03*
X219648Y576801D03*
X219485Y582348D03*
X218801Y571096D03*
X232167Y554962D03*
X219627Y562552D03*
X219691Y557104D03*
X225932Y548276D03*
X359929Y626617D03*
X384365Y605713D03*
X729930Y211940D03*
X723210Y209850D03*
X709650Y249400D03*
X714100Y238800D03*
X711000Y232800D03*
X722961Y300982D03*
X720530Y312210D03*
X733696Y300991D03*
X726800Y313113D03*
X727996Y303699D03*
X711322Y294199D03*
X706997Y283155D03*
X711029Y279114D03*
X713789Y284135D03*
X697960Y292400D03*
X703526Y275939D03*
X714519Y275114D03*
X707604Y272070D03*
X698773Y278597D03*
X709600Y299400D03*
X718600Y304300D03*
X715200Y300000D03*
X709500Y308400D03*
X693200Y279550D03*
X702109Y297903D03*
X702400Y286700D03*
X700700Y305100D03*
X716060Y309320D03*
X706600Y303800D03*
X691774Y288967D03*
X714400Y268600D03*
X718260Y294951D03*
X744960Y197430D03*
X797500Y226000D03*
X791140Y247740D03*
X753479Y207914D03*
X752700Y214100D03*
X744768Y300864D03*
X748100Y281300D03*
X748000Y288000D03*
X741100Y307400D03*
X739100Y302126D03*
X736952Y311391D03*
X743800Y278600D03*
X736800Y278300D03*
X815670Y242890D03*
X820100Y252600D03*
X802000Y232500D03*
X823100Y225400D03*
X811000Y234300D03*
X816400Y235900D03*
X807000Y230500D03*
X812630Y249229D03*
X828781Y231061D03*
X806400Y257300D03*
G54D57*
X733369Y481247D03*
G54D58*
X755785Y91500D03*
X753585D03*
X755785Y94000D03*
X753585D03*
X755784Y99500D03*
X753584D03*
X755784Y102000D03*
X753584D03*
X755785Y83500D03*
X753585D03*
X755785Y75500D03*
X753585D03*
X755785Y78000D03*
X753585D03*
X755785Y86000D03*
X753585D03*
X778900Y206500D03*
X776700D03*
X792802Y206042D03*
X790602D03*
X760500Y204300D03*
X758300D03*
X778900Y208700D03*
X776700D03*
X792802Y208542D03*
X790602D03*
X760608Y284964D03*
X758408D03*
X789600Y280500D03*
X787400D03*
X781740Y269030D03*
X779540D03*
X765979Y284964D03*
X763779D03*
X807316Y206045D03*
X805116D03*
X807256Y208363D03*
X805056D03*
X806068Y278464D03*
X803868D03*
X805868Y270664D03*
X803668D03*
G54D49*
X354800Y612600D03*
X351200D03*
X773200Y262450D03*
X769600D03*
X778390Y247880D03*
X774790D03*
X778550Y251850D03*
X774950D03*
G54D59*
X750150Y255200D03*
X752350D03*
X750300Y248900D03*
X752500D03*
X744000Y257400D03*
X746200D03*
X762600Y255200D03*
X764800D03*
X762600Y257400D03*
X764800D03*
X768700Y255150D03*
X770900D03*
X762550Y248900D03*
X764750D03*
X744050Y244850D03*
X746250D03*
X768700Y257350D03*
X770900D03*
X756400Y257400D03*
X758600D03*
X762550Y251100D03*
X764750D03*
X756400Y242600D03*
X758600D03*
X768950Y248940D03*
X771150D03*
X756400Y244800D03*
X758600D03*
X744050Y242600D03*
X746250D03*
X744000Y255200D03*
X746200D03*
X750300Y251100D03*
X752500D03*
X750207Y244805D03*
X752407D03*
X750200Y242600D03*
X752400D03*
X756400Y255200D03*
X758600D03*
X750150Y257400D03*
X752350D03*
X756450Y248900D03*
X758650D03*
X756450Y251100D03*
X758650D03*
X762600Y242600D03*
X764800D03*
X762600Y244800D03*
X764800D03*
X768950Y251140D03*
X771150D03*
X799400Y309500D03*
Y307000D03*
X788000Y269000D03*
X790200D03*
X780410Y276020D03*
X782610D03*
X780100Y279980D03*
X782300D03*
X775890Y284820D03*
X778090D03*
X786293Y285800D03*
X788493D03*
X785390Y266010D03*
X787590D03*
X786020Y283030D03*
X788220D03*
X801600Y309500D03*
Y307000D03*
X803800Y273800D03*
X806000D03*
M02*
